G04 ================== begin FILE IDENTIFICATION RECORD ==================*
G04 Layout Name:  9054_F0T_PDB_BD_GPU_F_V04_1213_1550.brd*
G04 Film Name:    top*
G04 File Format:  Gerber RS274X*
G04 File Origin:  Cadence Allegro 17.2-S081*
G04 Origin Date:  Wed Dec 28 10:19:01 2022*
G04 *
G04 Layer:  DRAWING FORMAT/TITLE_BLOCK_A*
G04 Layer:  PIN/SPECIAL_DRILL*
G04 Layer:  DRAWING FORMAT/TITLE_BLOCK*
G04 Layer:  VIA CLASS/TOP*
G04 Layer:  PIN/TOP*
G04 Layer:  MANUFACTURING/PHOTOPLOT_OUTLINE*
G04 Layer:  ETCH/TOP*
G04 Layer:  DRAWING FORMAT/TITLE_DATA_TOP*
G04 *
G04 Offset:    (0.00 0.00)*
G04 Mirror:    No*
G04 Mode:      Positive*
G04 Rotation:  0*
G04 FullContactRelief:  No*
G04 UndefLineWidth:     6.00*
G04 ================== end FILE IDENTIFICATION RECORD ====================*
%FSLAX25Y25*MOIN*%
%IR0*IPPOS*OFA0.00000B0.00000*MIA0B0*SFA1.00000B1.00000*%
%AMMACRO84*
4,1,32,-.01575,.06201,
-.01575,.0502,
.00197,.0502,
.00197,.04035,
-.01575,.04035,
-.01575,.03248,
.00197,.03248,
.00197,.02461,
-.01575,.02461,
-.01575,.01673,
.00197,.01673,
.00197,.00886,
-.01575,.00886,
-.01575,.00098,
.00197,.00098,
.00197,-.00689,
-.01575,-.00689,
-.01575,-.01476,
.00197,-.01476,
.00197,-.02264,
-.01575,-.02264,
-.01575,-.03051,
.00197,-.03051,
.00197,-.03839,
-.01575,-.03839,
-.01575,-.04626,
.00197,-.04626,
.00197,-.05413,
-.01575,-.05413,
-.01575,-.06201,
.01575,-.06201,
.01575,.06201,
-.01575,.06201,
0.0*
%
%ADD84MACRO84*%
%ADD39R,.122X.052*%
%ADD22R,.052X.122*%
%ADD88O,.123X.074*%
%AMMACRO23*
4,1,8,-.20866,.16634,
-.20866,.07776,
-.14764,.07776,
-.14764,-.16634,
.14764,-.16634,
.14764,.07776,
.20866,.07776,
.20866,.16634,
-.20866,.16634,
0.0*
%
%ADD23MACRO23*%
%ADD11C,.02*%
%ADD85R,.032X.007*%
%AMMACRO41*
4,1,8,.16634,.20866,
.07776,.20866,
.07776,.14764,
-.16634,.14764,
-.16634,-.14764,
.07776,-.14764,
.07776,-.20866,
.16634,-.20866,
.16634,.20866,
0.0*
%
%ADD41MACRO41*%
%ADD15C,.03*%
%ADD89C,.061*%
%ADD78R,.063X.119*%
%ADD77R,.138X.063*%
%ADD24C,.07*%
%ADD33R,.13X.099*%
%ADD26R,.063X.138*%
%ADD67C,.018*%
%ADD35C,.083*%
%ADD59C,.066*%
%ADD54C,.06015*%
%ADD17C,.039*%
%ADD37C,.085*%
%ADD90C,.086*%
%ADD36C,.095*%
%ADD25R,.07X.07*%
%ADD20C,.04552*%
%ADD58R,.066X.066*%
%ADD57R,.06015X.06015*%
%AMMACRO30*
4,1,28,-.00748,-.00052,
-.00984,-.00052,
-.00984,-.00603,
-.009782,-.006705,
-.009607,-.007359,
-.009321,-.007974,
-.008933,-.008529,
-.008455,-.009009,
-.0079,-.009398,
-.007286,-.009685,
-.006632,-.009861,
-.005957,-.00992,
-.00591,-.00992,
.00591,-.00992,
.006585,-.009869,
.007242,-.009701,
.007859,-.009421,
.008418,-.009039,
.008903,-.008565,
.009297,-.008015,
.009591,-.007404,
.009773,-.006751,
.00984,-.006077,
.00984,-.00603,
.00984,-.00052,
.00748,-.00052,
.00748,.00991,
-.00748,.00991,
-.00748,-.00052,
0.0*
%
%ADD30MACRO30*%
%AMMACRO70*
4,1,5,.00492,.01673,
-.00492,.01673,
-.00492,-.01673,
.00098,-.01673,
.00492,-.0128,
.00492,.01673,
0.0*
%
%ADD70MACRO70*%
%AMMACRO51*
4,1,28,-.00052,.00748,
-.00052,.00984,
-.00603,.00984,
-.006705,.009782,
-.007359,.009607,
-.007974,.009321,
-.008529,.008933,
-.009009,.008455,
-.009398,.0079,
-.009685,.007286,
-.009861,.006632,
-.00992,.005957,
-.00992,.00591,
-.00992,-.00591,
-.009869,-.006585,
-.009701,-.007242,
-.009421,-.007859,
-.009039,-.008418,
-.008565,-.008903,
-.008015,-.009297,
-.007404,-.009591,
-.006751,-.009773,
-.006077,-.00984,
-.00603,-.00984,
-.00052,-.00984,
-.00052,-.00748,
.00991,-.00748,
.00991,.00748,
-.00052,.00748,
0.0*
%
%ADD51MACRO51*%
%ADD21R,.04552X.04552*%
%AMMACRO34*
4,1,28,-.00748,.00051,
-.00984,.00051,
-.00984,.00602,
-.009782,.006695,
-.009607,.007349,
-.009321,.007964,
-.008933,.008519,
-.008455,.008998,
-.0079,.009388,
-.007287,.009675,
-.006632,.009851,
-.005958,.00991,
-.00591,.00991,
.00591,.00991,
.006585,.009859,
.007242,.009691,
.007859,.009411,
.008418,.009029,
.008903,.008555,
.009297,.008005,
.00959,.007394,
.009773,.006742,
.00984,.006068,
.00984,.00602,
.00984,.00051,
.00748,.00051,
.00748,-.00992,
-.00748,-.00992,
-.00748,.00051,
0.0*
%
%ADD34MACRO34*%
%AMMACRO50*
4,1,28,.00051,.00748,
.00051,.00984,
.00602,.00984,
.006695,.009782,
.007349,.009607,
.007964,.009321,
.008519,.008933,
.008998,.008455,
.009388,.0079,
.009675,.007287,
.009851,.006632,
.00991,.005958,
.00991,.00591,
.00991,-.00591,
.009859,-.006585,
.009691,-.007242,
.009411,-.007859,
.009029,-.008418,
.008555,-.008903,
.008005,-.009297,
.007394,-.00959,
.006742,-.009773,
.006068,-.00984,
.00602,-.00984,
.00051,-.00984,
.00051,-.00748,
-.00992,-.00748,
-.00992,.00748,
.00051,.00748,
0.0*
%
%ADD50MACRO50*%
%AMMACRO69*
4,1,8,-.01821,.0246,
.01821,.0246,
.01821,.01476,
-.00837,.01476,
-.00837,-.01477,
.01821,-.01477,
.01821,-.02461,
-.01821,-.02461,
-.01821,.0246,
0.0*
%
%ADD69MACRO69*%
%AMMACRO82*
4,1,5,.01772,.00591,
-.01772,.00591,
-.01772,0.0,
-.01181,-.00591,
.01772,-.00591,
.01772,.00591,
0.0*
%
%ADD82MACRO82*%
%ADD45R,.01X.02*%
%ADD65R,.032X.01*%
%ADD66R,.01X.032*%
%ADD64R,.01X.05*%
%ADD80R,.032X.012*%
%ADD52R,.032X.022*%
%ADD27R,.05X.04*%
%ADD83R,.04X.05*%
%ADD63R,.02X.018*%
%AMMACRO61*
4,1,8,-.16634,-.20866,
-.07776,-.20866,
-.07776,-.14764,
.16634,-.14764,
.16634,.14764,
-.07776,.14764,
-.07776,.20866,
-.16634,.20866,
-.16634,-.20866,
0.0*
%
%ADD61MACRO61*%
%ADD28R,.032X.024*%
%ADD42R,.018X.02*%
%ADD29R,.063X.04*%
%ADD12C,.4*%
%ADD53R,.036X.032*%
%ADD43R,.126X.27*%
%ADD18R,.04X.063*%
%ADD60R,.032X.036*%
%ADD49R,.017X.024*%
%ADD44R,.032X.028*%
%ADD76R,.028X.024*%
%ADD75R,.052X.018*%
%ADD74R,.056X.014*%
%ADD40R,.028X.032*%
%ADD48R,.054X.044*%
%ADD19R,.024X.028*%
%ADD10C,.125*%
%ADD87C,.414*%
%ADD79R,.138X.128*%
%ADD73R,.068X.022*%
%ADD56C,.315*%
%ADD38R,.044X.054*%
%ADD14O,.355X.552*%
%ADD72R,.022X.068*%
%ADD68R,.059X.014*%
%ADD81R,.012X.079*%
%ADD16C,.158*%
%ADD86R,.042X.099*%
%ADD71R,.089X.085*%
%AMMACRO47*
4,1,28,.00052,-.00748,
.00052,-.00984,
.00603,-.00984,
.006705,-.009782,
.007359,-.009607,
.007974,-.009321,
.008529,-.008933,
.009009,-.008455,
.009398,-.0079,
.009685,-.007286,
.009861,-.006632,
.00992,-.005957,
.00992,-.00591,
.00992,.00591,
.009869,.006585,
.009701,.007242,
.009421,.007859,
.009039,.008418,
.008565,.008903,
.008015,.009297,
.007404,.009591,
.006751,.009773,
.006077,.00984,
.00603,.00984,
.00052,.00984,
.00052,.00748,
-.00991,.00748,
-.00991,-.00748,
.00052,-.00748,
0.0*
%
%ADD47MACRO47*%
%AMMACRO32*
4,1,28,.00748,.00052,
.00984,.00052,
.00984,.00603,
.009782,.006705,
.009607,.007359,
.009321,.007974,
.008933,.008529,
.008455,.009009,
.0079,.009398,
.007286,.009685,
.006632,.009861,
.005957,.00992,
.00591,.00992,
-.00591,.00992,
-.006585,.009869,
-.007242,.009701,
-.007859,.009421,
-.008418,.009039,
-.008903,.008565,
-.009297,.008015,
-.009591,.007404,
-.009773,.006751,
-.00984,.006077,
-.00984,.00603,
-.00984,.00052,
-.00748,.00052,
-.00748,-.00991,
.00748,-.00991,
.00748,.00052,
0.0*
%
%ADD32MACRO32*%
%ADD62R,.099X.067*%
%AMMACRO46*
4,1,28,-.00051,-.00748,
-.00051,-.00984,
-.00602,-.00984,
-.006695,-.009782,
-.007349,-.009607,
-.007964,-.009321,
-.008519,-.008933,
-.008998,-.008455,
-.009388,-.0079,
-.009675,-.007287,
-.009851,-.006632,
-.00991,-.005958,
-.00991,-.00591,
-.00991,.00591,
-.009859,.006585,
-.009691,.007242,
-.009411,.007859,
-.009029,.008418,
-.008555,.008903,
-.008005,.009297,
-.007394,.00959,
-.006742,.009773,
-.006068,.00984,
-.00602,.00984,
-.00051,.00984,
-.00051,.00748,
.00992,.00748,
.00992,-.00748,
-.00051,-.00748,
0.0*
%
%ADD46MACRO46*%
%AMMACRO31*
4,1,28,.00748,-.00051,
.00984,-.00051,
.00984,-.00602,
.009782,-.006695,
.009607,-.007349,
.009321,-.007964,
.008933,-.008519,
.008455,-.008998,
.0079,-.009388,
.007287,-.009675,
.006632,-.009851,
.005958,-.00991,
.00591,-.00991,
-.00591,-.00991,
-.006585,-.009859,
-.007242,-.009691,
-.007859,-.009411,
-.008418,-.009029,
-.008903,-.008555,
-.009297,-.008005,
-.00959,-.007394,
-.009773,-.006742,
-.00984,-.006068,
-.00984,-.00602,
-.00984,-.00051,
-.00748,-.00051,
-.00748,.00992,
.00748,.00992,
.00748,-.00051,
0.0*
%
%ADD31MACRO31*%
%ADD91C,.01*%
%ADD92C,.014*%
%ADD93C,.015*%
%ADD94C,.025*%
%ADD95C,.006*%
%ADD96C,.0051*%
%ADD97C,.007*%
%ADD98C,.0068*%
%ADD103C,.03004*%
%ADD108C,.04004*%
%ADD107C,.03006*%
%ADD113C,.07604*%
%ADD104C,.05556*%
%ADD105C,.05558*%
%ADD100C,.22004*%
%ADD99C,.17004*%
%ADD114C,.26006*%
%ADD111C,.32504*%
%ADD112C,.12606*%
%ADD102C,.11706*%
%ADD115C,.12806*%
%ADD101C,.11708*%
%ADD106C,.16506*%
%ADD109C,.19802*%
%ADD110C,.19806*%
G75*
%LPD*%
G75*
G36*
G01X124047Y646482D02*
X126046D01*
Y642913D01*
G02X102362Y619229I-23684J0D01*
G01X19685D01*
G03X3999Y603543I0J-15686D01*
G01Y19685D01*
G03X19685Y3999I15686J0D01*
G01X226600D01*
Y2000D01*
X19685D01*
G02X2000Y19685I0J17685D01*
G01Y603543D01*
G02X19685Y621228I17685J0D01*
G01X102362D01*
G03X124047Y642913I0J21685D01*
G01Y646482D01*
G37*
G36*
G01X135200Y667100D02*
X147255D01*
X147733Y666622D01*
Y592061D01*
X149556Y590238D01*
X178523D01*
X179974Y591689D01*
Y633225D01*
X183249Y636500D01*
X202738D01*
G03X213010I5136J2594D01*
G01X304478D01*
X304852Y636126D01*
Y608421D01*
X289242Y592811D01*
Y592783D01*
X288132Y591673D01*
Y547533D01*
X300913Y534752D01*
X329443D01*
X335000Y529195D01*
Y360600D01*
X401843Y293757D01*
X440418D01*
G03X440560Y293698I142J141D01*
G01X467524D01*
X468338Y292884D01*
Y275485D01*
X467255Y274402D01*
X426502D01*
X425500Y273400D01*
Y250800D01*
X426943Y249357D01*
X434343D01*
X434402Y249298D01*
X467524D01*
X468338Y248484D01*
Y231085D01*
X467255Y230002D01*
X426802D01*
X425500Y228700D01*
Y206400D01*
X426943Y204957D01*
X440418D01*
G03X440560Y204898I142J141D01*
G01X467524D01*
X468338Y204084D01*
Y186685D01*
X467255Y185602D01*
X426902D01*
X425400Y184100D01*
Y161900D01*
X426743Y160557D01*
X440418D01*
G03X440560Y160498I142J141D01*
G01X467524D01*
X468338Y159684D01*
Y142285D01*
X467255Y141202D01*
X427102D01*
X425400Y139500D01*
Y117800D01*
X427043Y116157D01*
X440418D01*
G03X440560Y116098I142J141D01*
G01X467524D01*
X468338Y115284D01*
Y97885D01*
X467255Y96802D01*
X427402D01*
X425400Y94800D01*
Y73000D01*
X426800Y71600D01*
X440261D01*
X440359Y71698D01*
X467524D01*
X468338Y70884D01*
Y53485D01*
X467255Y52402D01*
X399479D01*
X392598D01*
X392338Y52662D01*
Y59460D01*
X392169Y59629D01*
X356272Y95526D01*
X322437D01*
X283963Y134000D01*
X240621D01*
X237185Y137436D01*
X201364D01*
X198001Y140799D01*
X188081D01*
X186285Y139003D01*
G03X182648Y135366I3165J-6802D01*
G01X181549Y134267D01*
X152021D01*
Y152575D01*
X144246Y160350D01*
X137584D01*
Y166650D01*
X134083Y170151D01*
Y665983D01*
X135200Y667100D01*
G37*
G36*
G01X155434Y667320D02*
X304133D01*
G02X304275Y667261I0J-200D01*
G01X305668Y665868D01*
G02X305727Y665726I-141J-142D01*
G01Y648070D01*
G02X305668Y647928I-200J0D01*
G01X304463Y646723D01*
G02X304321Y646664I-142J141D01*
G01X167838D01*
G03X167696Y646605I0J-200D01*
G01X166240Y645149D01*
G03X166181Y645007I141J-142D01*
G01Y600525D01*
G02X166122Y600383I-200J0D01*
G01X165107Y599368D01*
G02X164965Y599309I-142J141D01*
G01X155330D01*
X155257Y599339D01*
X155234Y599362D01*
Y667120D01*
G02X155434Y667320I200J0D01*
G37*
G36*
G01X1437008Y673787D02*
X1590551D01*
G02X1608236Y656102I0J-17685D01*
G01Y642913D01*
G03X1629921Y621228I21685J0D01*
G01X1712598D01*
G02X1730283Y603543I0J-17685D01*
G01Y538465D01*
G03X1751968Y516780I21685J0D01*
G01X1854331D01*
G02X1872016Y499095I0J-17685D01*
G01Y85709D01*
G02X1854331Y68024I-17685J0D01*
G01X1751968D01*
G03X1730283Y46339I1J-21686D01*
G01Y19685D01*
G02X1712598Y2000I-17685J0D01*
G01X1495618D01*
Y3999D01*
X1712598D01*
G03X1728284Y19685I0J15686D01*
G01Y46339D01*
G02X1751968Y70023I23685J-1D01*
G01X1854331D01*
G03X1870017Y85709I0J15686D01*
G01Y499095D01*
G03X1854331Y514781I-15686J0D01*
G01X1751968D01*
G02X1728284Y538465I1J23684D01*
G01Y603543D01*
G03X1712598Y619229I-15686J0D01*
G01X1629921D01*
G02X1606237Y642913I0J23684D01*
G01Y656102D01*
G03X1590551Y671788I-15686J0D01*
G01X1437008D01*
G03X1421322Y656102I0J-15686D01*
G01Y635039D01*
G02X1405512Y619229I-15810J0D01*
G01X1403543D01*
G03X1387857Y603543I0J-15686D01*
G01Y435039D01*
G02X1354331Y401513I-33526J0D01*
G01X377952D01*
G02X344426Y435039I1J33527D01*
G01Y603543D01*
G03X328740Y619229I-15686J0D01*
G01X326772D01*
G02X310962Y635039I0J15810D01*
G01Y656102D01*
G03X295276Y671788I-15686J0D01*
G01X153969D01*
Y673787D01*
X295276D01*
G02X312961Y656102I0J-17685D01*
G01Y635039D01*
G03X326772Y621228I13811J0D01*
G01X328740D01*
G02X346425Y603543I0J-17685D01*
G01Y435039D01*
G03X377952Y403512I31528J1D01*
G01X1354331D01*
G03X1385858Y435039I0J31527D01*
G01Y603543D01*
G02X1403543Y621228I17685J0D01*
G01X1405512D01*
G03X1419323Y635039I0J13811D01*
G01Y656102D01*
G02X1437008Y673787I17685J0D01*
G37*
G36*
G01X191644Y100000D02*
X206978D01*
G02X207120Y99941I0J-200D01*
G01X208002Y99059D01*
G02X208061Y98917I-141J-142D01*
G01Y65583D01*
G02X208002Y65441I-200J0D01*
G01X206620Y64059D01*
G02X206478Y64000I-142J141D01*
G01X192644D01*
G02X192502Y64059I0J200D01*
G01X191120Y65441D01*
G02X191061Y65583I141J142D01*
G01Y99417D01*
G02X191120Y99559I200J0D01*
G01X191502Y99941D01*
G02X191644Y100000I142J-141D01*
G37*
G36*
G01X174188Y116379D02*
X179382D01*
G02X179582Y116193I0J-201D01*
G01Y107904D01*
X186328D01*
G02X186514Y107704I-15J-200D01*
G01Y107578D01*
X186489Y107512D01*
X186465Y107484D01*
G03Y105516I1136J-984D01*
G01X186514Y105385D01*
Y67561D01*
G02X186455Y67419I-200J0D01*
G01X184985Y65949D01*
G02X184843Y65890I-142J141D01*
G01X172466D01*
G02X172324Y65949I0J200D01*
G01X172046Y66227D01*
G02X171987Y66369I141J142D01*
G01Y107704D01*
G02X172173Y107904I201J0D01*
G01X173988D01*
Y116193D01*
G02X174188Y116379I200J-15D01*
G37*
G36*
G01X881120Y28838D02*
X1423134D01*
G02X1423275Y28780I0J-200D01*
G01X1424451Y27604D01*
G02X1424510Y27462I-141J-142D01*
G01Y15333D01*
G03X1424569Y15191I200J0D01*
G01X1424652Y15108D01*
X1424682Y15043D01*
X1424684Y15007D01*
G03X1437098Y11862I6733J505D01*
G02X1437349Y11935I168J-109D01*
G03X1441417Y11049I4067J8892D01*
G03X1446317Y12365I1J9778D01*
G02X1446517I100J-173D01*
G03X1451416Y11049I4899J8462D01*
G01X1451417D01*
G03X1453397Y11252I-2J9778D01*
G01X1453442Y11261D01*
X1453528Y11240D01*
X1453804Y11015D01*
G02X1453878Y10860I-126J-155D01*
G01Y4811D01*
G02X1453819Y4669I-200J0D01*
G01X1452944Y3794D01*
G02X1452802Y3735I-142J141D01*
G01X324438D01*
G02X324296Y3794I0J200D01*
G01X322431Y5659D01*
G02X322372Y5801I141J142D01*
G01Y27152D01*
G02X322431Y27294I200J0D01*
G01X323637Y28500D01*
X356300D01*
X356638Y28838D01*
X854019D01*
X854132Y28736D01*
X854140Y28658D01*
G03X862212Y21007I8460J842D01*
G02X862315Y20972I-10J-200D01*
G03X867099Y19498I4785J7028D01*
G01X867100D01*
G03X871805Y20919I-1J8502D01*
G02X871930Y20951I109J-167D01*
G03X872533Y20930I597J8481D01*
G03X881000Y28657I0J8502D01*
G01X881007Y28735D01*
X881120Y28838D01*
G37*
G36*
G01X468484Y79200D02*
X443584D01*
X443384Y79400D01*
Y84300D01*
X443584Y84500D01*
X468484D01*
X468584Y84400D01*
Y79300D01*
X468484Y79200D01*
G37*
G36*
G01Y123600D02*
X443584D01*
X443384Y123800D01*
Y128700D01*
X443584Y128900D01*
X468484D01*
X468584Y128800D01*
Y123700D01*
X468484Y123600D01*
G37*
G36*
G01Y168000D02*
X443584D01*
X443384Y168200D01*
Y173100D01*
X443584Y173300D01*
X468484D01*
X468584Y173200D01*
Y168100D01*
X468484Y168000D01*
G37*
G36*
G01Y212400D02*
X443584D01*
X443384Y212600D01*
Y217500D01*
X443584Y217700D01*
X468484D01*
X468584Y217600D01*
Y212500D01*
X468484Y212400D01*
G37*
G36*
G01Y256800D02*
X443584D01*
X443384Y257000D01*
Y261900D01*
X443584Y262100D01*
X468484D01*
X468584Y262000D01*
Y256900D01*
X468484Y256800D01*
G37*
G36*
G01Y301200D02*
X443584D01*
X443384Y301400D01*
Y306300D01*
X443584Y306500D01*
X468484D01*
X468584Y306400D01*
Y301300D01*
X468484Y301200D01*
G37*
G36*
G01X486284Y180600D02*
X487384Y181700D01*
X559000D01*
X560446Y180254D01*
Y165546D01*
X554400Y159500D01*
X547000D01*
X541500Y154000D01*
Y131400D01*
X543000Y129900D01*
X560284D01*
X560484Y129700D01*
Y119000D01*
X558984Y117500D01*
Y115200D01*
X560449Y113735D01*
Y51465D01*
X559784Y50800D01*
X487584D01*
X486284Y52100D01*
Y180600D01*
G37*
G36*
G01X519884Y314900D02*
X487384D01*
X486284Y313800D01*
Y185300D01*
X487584Y184000D01*
X519784D01*
X559784D01*
X560449Y184665D01*
Y246428D01*
Y246935D01*
X558984Y248400D01*
Y250500D01*
Y250600D01*
Y250700D01*
X560484Y252200D01*
Y262900D01*
X560284Y263100D01*
X541684D01*
X536884Y267900D01*
Y313500D01*
X535484Y314900D01*
X529784D01*
X519884D01*
G37*
G36*
G01X565685Y262968D02*
X584461D01*
X585328Y262101D01*
X588429Y259000D01*
Y237811D01*
X590940Y235300D01*
X591200D01*
X602300D01*
X615400Y222200D01*
X625025D01*
X631297Y215928D01*
X672272D01*
X688500D01*
X689100Y215328D01*
Y211900D01*
X682700Y205500D01*
X674900D01*
X668272Y198872D01*
Y177628D01*
X683238Y162662D01*
X755950D01*
X778988Y185700D01*
X825584D01*
X826725Y184559D01*
G02X826784Y184417I-141J-142D01*
G01Y119746D01*
X826754Y119716D01*
Y119337D01*
G02X826695Y119195I-200J0D01*
G01X822545Y115045D01*
X637425D01*
X629600Y107220D01*
Y63900D01*
X623700Y58000D01*
X567300D01*
X565554Y59746D01*
Y113755D01*
X567116Y115317D01*
Y117384D01*
X565555Y118945D01*
Y129638D01*
X565685Y129768D01*
X582268D01*
X584034Y131534D01*
Y152034D01*
X576568Y159500D01*
X571700D01*
X565500Y165700D01*
Y184500D01*
X565554D01*
Y246955D01*
X567116Y248517D01*
Y250584D01*
X565555Y252145D01*
Y262838D01*
X565685Y262968D01*
G37*
G36*
G01X686338Y289804D02*
X696527D01*
G02X696669Y289745I0J-200D01*
G01X697852Y288562D01*
G02X697911Y288420I-141J-142D01*
G01Y270939D01*
G03X697970Y270797I200J0D01*
G01X702653Y266114D01*
Y245970D01*
X701812Y245129D01*
G02X701670Y245070I-142J141D01*
G01X699013D01*
X698092D01*
X697440Y245722D01*
Y249468D01*
X696820Y250088D01*
X694553D01*
G02X694411Y250147I0J200D01*
G01X694063Y250495D01*
G02X694004Y250637I141J142D01*
G01Y262438D01*
G03X693945Y262580I-200J0D01*
G01X692696Y263829D01*
G03X692554Y263888I-142J-141D01*
G01X686534D01*
G02X686392Y263947I0J200D01*
G01X685403Y264936D01*
G02X685344Y265078I141J142D01*
G01Y288810D01*
G02X685403Y288952I200J0D01*
G01X686196Y289745D01*
G02X686338Y289804I142J-141D01*
G37*
G36*
G01X720245Y200520D02*
X758810D01*
X760284Y199046D01*
Y183828D01*
X746956Y170500D01*
X732779D01*
X719272Y184007D01*
Y199547D01*
X720245Y200520D01*
G37*
G36*
G01X1175654Y262968D02*
X1196599D01*
X1196729Y262838D01*
Y252145D01*
X1195168Y250584D01*
Y248517D01*
X1196730Y246955D01*
Y175130D01*
X1188100Y166500D01*
X1188000D01*
X1175716Y154216D01*
Y131155D01*
X1177103Y129768D01*
X1196599D01*
X1196729Y129638D01*
Y118945D01*
X1195168Y117384D01*
Y115317D01*
X1196730Y113755D01*
Y57100D01*
X1196630Y57000D01*
X1110024D01*
X1101400Y65624D01*
Y106859D01*
X1093214Y115045D01*
X1091057D01*
X907614D01*
G02X907472Y115104I0J200D01*
G01X905559Y117017D01*
G02X905500Y117159I141J142D01*
G01Y184417D01*
G02X905559Y184559I200J0D01*
G01X906500Y185500D01*
X956600D01*
X979438Y162662D01*
X1008462D01*
X1019300Y173500D01*
X1056700D01*
X1112150Y228950D01*
X1156150D01*
X1174143Y246943D01*
Y261457D01*
X1175654Y262968D01*
G37*
G36*
G01X974461Y200520D02*
X1013026D01*
X1014500Y199046D01*
Y183828D01*
X1001172Y170500D01*
X986995D01*
X973488Y184007D01*
Y199547D01*
X974461Y200520D01*
G37*
G36*
G01X1082983Y314400D02*
X1097372D01*
G02X1097557Y314276I0J-200D01*
G01X1097721Y313879D01*
X1097697Y313760D01*
X1097654Y313717D01*
G03X1095159Y307700I6008J-6017D01*
G03X1097014Y302399I8502J0D01*
G01X1097050Y302354D01*
X1097063Y302239D01*
X1096882Y301863D01*
G02X1096701Y301750I-180J87D01*
G01X1096266D01*
G02X1096066Y301950I0J200D01*
G01Y301986D01*
X1095013D01*
G03X1094123Y301089I0J-890D01*
G01X1094124D01*
Y301079D01*
G02X1094065Y300937I-200J0D01*
G01X1086151Y293024D01*
G03X1085758Y292075I949J-949D01*
G01Y287139D01*
G02X1085700Y286997I-200J-1D01*
G01X1083651Y284949D01*
G03X1083258Y284000I949J-949D01*
G01Y281093D01*
G02X1083201Y280953I-200J0D01*
G01X1083118Y280868D01*
G02X1082987Y280809I-142J141D01*
G03X1081098Y278810I113J-1999D01*
G03X1083100Y276808I2002J0D01*
G03X1084310Y277215I0J2002D01*
G01X1084342Y277239D01*
X1084420Y277259D01*
X1084784Y277204D01*
X1084853Y277161D01*
X1084877Y277128D01*
G03X1084988Y276990I1224J871D01*
G01X1085028Y276946D01*
X1085047Y276830D01*
X1084875Y276441D01*
G02X1084692Y276322I-183J81D01*
G01X1082316D01*
G03X1081367Y275929I0J-1342D01*
G01X1078151Y272713D01*
G03X1077758Y271764I949J-949D01*
G01Y263451D01*
G02X1077700Y263309I-200J-1D01*
G01X1077349Y262959D01*
G02X1077208Y262900I-142J141D01*
G01X1066360D01*
X1065533Y263727D01*
Y294541D01*
X1056753Y303321D01*
Y313553D01*
X1057541Y314341D01*
G02X1057683Y314400I142J-141D01*
G01X1067317D01*
G02X1067459Y314341I0J-200D01*
G01X1067941Y313859D01*
G02X1068000Y313717I-141J-142D01*
G01Y306183D01*
G02X1067941Y306041I-200J0D01*
G01X1067387Y305487D01*
X1067298Y305458D01*
X1067250Y305465D01*
G03X1067025Y305482I-225J-1485D01*
G03Y302478I0J-1502D01*
G03X1068269Y303138I0J1502D01*
G02X1068434Y303226I166J-112D01*
G01X1068766D01*
G02X1068931Y303138I-1J-200D01*
G03X1070175Y302478I1244J842D01*
G03X1071434Y303161I0J1502D01*
G01X1071459Y303199D01*
X1071536Y303246D01*
X1071890Y303283D01*
G02X1072052Y303226I21J-199D01*
G01X1074700Y300578D01*
G02X1074758Y300436I-142J-141D01*
G01Y295639D01*
G02X1074700Y295497I-200J-1D01*
G01X1072869Y293666D01*
X1072827Y293651D01*
G03X1071859Y292493I512J-1412D01*
G01X1071850Y292443D01*
X1071791Y292366D01*
X1071400Y292186D01*
X1071303Y292191D01*
X1071259Y292217D01*
G03X1070490Y292429I-769J-1289D01*
G03X1068988Y290927I0J-1502D01*
G03X1069978Y289515I1502J0D01*
G01X1070020Y289500D01*
X1070609Y288910D01*
G03X1071558Y288518I948J950D01*
G01X1076659D01*
G03X1077608Y288910I1J1342D01*
G01X1079049Y290351D01*
G03X1079442Y291300I-949J949D01*
G01Y292256D01*
G02X1079532Y292423I200J0D01*
G01X1079854Y292634D01*
X1079954Y292643D01*
X1080001Y292623D01*
G03X1080600Y292498I600J1377D01*
G03X1082102Y294000I0J1502D01*
G03X1081960Y294637I-1502J0D01*
G01X1081942Y294677D01*
Y313359D01*
G02X1082000Y313500I200J0D01*
G01X1082841Y314341D01*
G02X1082983Y314400I142J-141D01*
G37*
G36*
G01X1112950D02*
X1118005D01*
G02X1118146Y314341I-1J-200D01*
G01X1121781Y310707D01*
X1122516Y309972D01*
G02X1122570Y309834I-146J-137D01*
G01Y295268D01*
G02X1122511Y295127I-200J1D01*
G01X1121765Y294380D01*
X1118051Y290667D01*
G03X1117658Y289718I949J-949D01*
G01Y287241D01*
G02X1117599Y287099I-200J0D01*
G01X1116059Y285559D01*
G03X1116000Y285417I141J-142D01*
G01Y275795D01*
G02X1115941Y275654I-200J1D01*
G01X1113188Y272901D01*
G02X1113047Y272842I-142J141D01*
G01X1102176D01*
X1102136Y272861D01*
G03X1101500Y273002I-635J-1361D01*
G03X1099998Y271500I0J-1502D01*
G03X1100123Y270901I1502J1D01*
G01X1100143Y270854D01*
X1100134Y270755D01*
X1099923Y270432D01*
G02X1099756Y270342I-167J110D01*
G01X1097600D01*
G03X1096651Y269949I0J-1342D01*
G01X1092471Y265768D01*
X1091630Y264927D01*
X1091588Y264912D01*
G03X1090598Y263500I512J-1412D01*
G03X1090606Y263341I1502J-4D01*
G01X1090611Y263298D01*
X1090585Y263218D01*
X1090357Y262966D01*
G02X1090209Y262900I-148J134D01*
G01X1080642D01*
G02X1080442Y263100I0J200D01*
G01Y271126D01*
G02X1080501Y271267I200J-1D01*
G01X1081339Y272106D01*
G02X1081491Y272164I141J-142D01*
G01X1081831Y272146D01*
X1081906Y272108D01*
X1081933Y272074D01*
G03X1083100Y271518I1167J947D01*
G03X1083736Y271659I1J1502D01*
G01X1083776Y271678D01*
X1083952D01*
G02X1084152Y271478I0J-200D01*
G01Y271453D01*
X1084146Y271428D01*
G03X1084098Y271053I1454J-377D01*
G01Y271050D01*
G03X1085600Y269548I1502J0D01*
G03X1086236Y269689I1J1502D01*
G01X1086276Y269708D01*
X1090150D01*
G03X1091099Y270101I0J1342D01*
G01X1096474Y275476D01*
G03X1096780Y275951I-950J948D01*
G03X1096866Y276425I-1255J473D01*
G01Y283433D01*
G02X1096960Y283602I200J-1D01*
G01X1097247Y283782D01*
G02X1097441Y283792I106J-170D01*
G03X1098025Y283658I585J1208D01*
G01X1103999D01*
X1104049Y283645D01*
X1104072Y283632D01*
G03X1104513Y283514I443J772D01*
G01X1105366D01*
X1105450D01*
X1105566Y283632D01*
Y283633D01*
X1105684Y283750D01*
X1106410D01*
X1106492D01*
X1106610Y283868D01*
Y283940D01*
Y285530D01*
G02X1106669Y285671I200J-1D01*
G01X1108570Y287573D01*
X1108612Y287588D01*
G03X1109602Y289000I-512J1412D01*
G03X1108100Y290502I-1502J0D01*
G03X1107239Y290231I0J-1503D01*
G01X1107192Y290198D01*
X1107082Y290191D01*
X1106718Y290381D01*
G02X1106610Y290558I92J177D01*
G01Y293227D01*
G02X1106669Y293369I200J0D01*
G01X1107541Y294241D01*
G02X1107683Y294300I142J-141D01*
G01X1115877D01*
G03X1116019Y294359I0J200D01*
G01X1116352Y294692D01*
G02X1116493Y294750I141J-142D01*
G01X1116610Y294867D01*
Y294940D01*
Y297050D01*
Y297132D01*
X1116492Y297250D01*
X1116420D01*
X1115766D01*
G02X1115566Y297450I0J200D01*
G01Y297486D01*
X1115480D01*
X1115437D01*
X1114665Y298257D01*
G02X1114622Y298475I142J141D01*
G01X1114645Y298532D01*
X1114745Y298598D01*
X1116200D01*
G03X1116702Y299100I0J502D01*
G01Y301900D01*
G03X1116200Y302402I-502J0D01*
G01X1116142D01*
G02X1115942Y302602I0J199D01*
G01Y302936D01*
G03X1115549Y303885I-1342J0D01*
G01X1114696Y304737D01*
X1114671Y304848D01*
X1114690Y304903D01*
G03X1115163Y307700I-8029J2796D01*
G03X1112668Y313717I-8503J0D01*
G02X1112613Y313819I141J142D01*
G02X1112624Y313935I196J40D01*
G01X1112765Y314276D01*
G02X1112839Y314366I185J-76D01*
G02X1112950Y314400I112J-166D01*
G37*
G36*
G01X1157302D02*
X1158417D01*
G02X1158559Y314341I0J-200D01*
G01X1165341Y307559D01*
G02X1165400Y307417I-141J-142D01*
G01Y301114D01*
G02X1165391Y301054I-200J-1D01*
G03X1164998Y298500I8109J-2555D01*
G03X1165391Y295946I8502J1D01*
G02X1165400Y295886I-191J-59D01*
G01Y270483D01*
G02X1165341Y270341I-200J0D01*
G01X1157959Y262959D01*
G02X1157817Y262900I-142J141D01*
G01X1116600D01*
X1116049Y263451D01*
Y268451D01*
X1124849Y277251D01*
G03X1125242Y278200I-949J949D01*
G01Y285200D01*
G03X1124849Y286149I-1342J0D01*
G01X1123027Y287970D01*
X1123012Y288012D01*
G03X1122960Y288137I-1411J-514D01*
G01X1122942Y288177D01*
Y288361D01*
G02X1123000Y288503I200J1D01*
G01X1127349Y292851D01*
G03X1127742Y293800I-949J949D01*
G01Y311700D01*
G03X1127349Y312649I-1342J0D01*
G01X1125938Y314059D01*
G02X1125895Y314277I142J141D01*
G01X1125919Y314333D01*
X1126018Y314400D01*
X1140094D01*
G02X1140273Y314288I-1J-200D01*
G01X1140457Y313915D01*
X1140445Y313801D01*
X1140410Y313756D01*
G03X1140188Y313351I1191J-916D01*
G01X1140173Y313309D01*
X1134245Y307382D01*
G03X1133956Y306951I949J-949D01*
G01X1133937Y306904D01*
X1133860Y306842D01*
X1133485Y306768D01*
G02X1133305Y306822I-39J196D01*
G01X1131937Y308190D01*
X1131922Y308232D01*
G03X1130510Y309222I-1412J-512D01*
G03X1129008Y307720I0J-1502D01*
G03X1129258Y306890I1503J0D01*
G01X1129279Y306858D01*
X1129295Y306786D01*
X1129240Y306443D01*
X1129202Y306378D01*
X1129172Y306355D01*
G03X1128598Y305174I928J-1181D01*
G03X1128740Y304537I1502J0D01*
G01X1128758Y304497D01*
Y269376D01*
G03X1129151Y268427I1342J0D01*
G01X1129945Y267634D01*
X1129975Y267561D01*
X1129974Y267520D01*
Y267500D01*
G03X1129982Y267325I2002J4D01*
G01X1129985Y267285D01*
X1129962Y267211D01*
X1129736Y266934D01*
X1129668Y266897D01*
X1129629Y266892D01*
G03X1128298Y265400I171J-1492D01*
G03X1129800Y263898I1502J0D01*
G03X1131285Y265176I0J1502D01*
G01X1131291Y265215D01*
X1131331Y265282D01*
X1131616Y265498D01*
X1131691Y265518D01*
X1131730Y265513D01*
G03X1131976Y265498I245J1987D01*
G03Y269502I0J2002D01*
G01X1131956D01*
X1131915Y269501D01*
X1131842Y269531D01*
X1131500Y269873D01*
G02X1131442Y270015I142J141D01*
G01Y272618D01*
G02X1131511Y272769I200J0D01*
G01X1131773Y272996D01*
X1131855Y273020D01*
X1131899Y273013D01*
G03X1132113Y272998I212J1487D01*
G03X1133615Y274500I0J1502D01*
G03X1133473Y275137I-1502J0D01*
G01X1133454Y275177D01*
Y275638D01*
X1133538Y275745D01*
X1133604Y275763D01*
G03X1135046Y277231I-504J1937D01*
G01X1135056Y277271D01*
X1135106Y277337D01*
X1135432Y277522D01*
X1135514Y277531D01*
X1135554Y277519D01*
G03X1136000Y277451I447J1434D01*
G03X1137502Y278953I0J1502D01*
G03X1136649Y280308I-1503J0D01*
G01X1136597Y280333D01*
X1136536Y280430D01*
Y305794D01*
G02X1136594Y305936I200J1D01*
G01X1142070Y311412D01*
X1142112Y311427D01*
G03X1143102Y312839I-512J1412D01*
G03X1142790Y313756I-1502J0D01*
G01X1142755Y313801D01*
X1142743Y313915D01*
X1142927Y314288D01*
G02X1143106Y314400I180J-88D01*
G01X1148758D01*
G02X1148958Y314200I0J-200D01*
G01Y301605D01*
G03X1149351Y300656I1342J0D01*
G01X1155082Y294926D01*
X1155097Y294884D01*
G03X1155571Y294223I1412J512D01*
G01X1155606Y294195D01*
X1155645Y294117D01*
X1155655Y293721D01*
X1155621Y293641D01*
X1155587Y293611D01*
G03X1155082Y292488I996J-1123D01*
G03X1156584Y290986I1502J0D01*
G03X1157996Y291976I0J1502D01*
G01X1158011Y292018D01*
X1159497Y293503D01*
G03X1159890Y294452I-949J949D01*
G01Y296552D01*
G03X1159497Y297501I-1342J0D01*
G01X1153580Y303417D01*
G02X1153522Y303559I142J141D01*
G01Y314200D01*
G02X1153722Y314400I200J0D01*
G01X1153898D01*
G02X1154098Y314200I0J-200D01*
G01Y304538D01*
G03X1154538Y303476I1502J0D01*
G01X1156076Y301938D01*
G03X1157138Y301498I1062J1062D01*
G03X1158640Y303000I0J1502D01*
G03X1158200Y304062I-1502J0D01*
G01X1157160Y305101D01*
G02X1157102Y305243I142J141D01*
G01Y314200D01*
G02X1157302Y314400I200J0D01*
G37*
G36*
G01X1202970Y181700D02*
X1274900D01*
X1276000Y180600D01*
Y52100D01*
X1274700Y50800D01*
X1242500D01*
X1240800Y52500D01*
X1203300D01*
X1201835Y53965D01*
Y113735D01*
X1203300Y115200D01*
Y117500D01*
X1201800Y119000D01*
Y129700D01*
X1202000Y129900D01*
X1220600D01*
X1225400Y134700D01*
Y154500D01*
X1218400Y161500D01*
X1215200D01*
X1201770Y174930D01*
Y180500D01*
X1202970Y181700D01*
G37*
G36*
G01X1242400Y314900D02*
X1274900D01*
X1276000Y313800D01*
Y185300D01*
X1274700Y184000D01*
X1242500D01*
X1202500D01*
X1201835Y184665D01*
Y246428D01*
Y246935D01*
X1203300Y248400D01*
Y250500D01*
Y250600D01*
Y250700D01*
X1201800Y252200D01*
Y262900D01*
X1202000Y263100D01*
X1220600D01*
X1225400Y267900D01*
Y313500D01*
X1226800Y314900D01*
X1232500D01*
X1242400D01*
G37*
G36*
G01X1564583Y667500D02*
X1577917D01*
G02X1578057Y667443I0J-200D01*
G01X1578556Y666944D01*
Y588944D01*
X1579558Y587942D01*
X1579559Y587941D01*
X1583441Y584059D01*
G03X1583583Y584000I142J141D01*
G01X1629417D01*
G02X1629557Y583943I0J-200D01*
G01X1633882Y579618D01*
G02X1633884Y579616I-140J-142D01*
G02X1633941Y579476I-143J-140D01*
G01Y538641D01*
G03X1633971Y538536I200J0D01*
G01X1633985Y538512D01*
X1634000Y538460D01*
Y220200D01*
X1633970Y220126D01*
X1633941Y220098D01*
X1623560Y209717D01*
Y199460D01*
X1621159Y197059D01*
X1621131Y197030D01*
X1621057Y197000D01*
X1610926D01*
G03X1610784Y196941I0J-200D01*
G01X1597560Y183717D01*
Y163300D01*
X1596851D01*
X1594701Y161150D01*
Y154850D01*
X1588950D01*
X1582900Y148800D01*
Y129800D01*
X1581367Y128267D01*
X1550233D01*
X1544260Y134240D01*
G03X1544118Y134299I-142J-141D01*
G01X1534082D01*
G03X1533940Y134240I0J-200D01*
G01X1531195Y131495D01*
G02X1531053Y131436I-142J141D01*
G01X1449078D01*
G03X1448936Y131377I0J-200D01*
G01X1399812Y82253D01*
X1399805Y82247D01*
X1395117Y77559D01*
G02X1394975Y77500I-142J141D01*
G01X1294108D01*
G02X1293966Y77559I0J200D01*
G01X1293659Y77866D01*
X1293630Y77894D01*
X1293600Y77968D01*
Y95998D01*
G02X1293800Y96198I200J0D01*
G01X1333215D01*
G03X1333357Y96257I0J200D01*
G01X1336541Y99441D01*
G03X1336600Y99583I-141J142D01*
G01Y117917D01*
G03X1336541Y118059I-200J0D01*
G01X1333257Y121343D01*
G03X1333115Y121402I-142J-141D01*
G01X1294142D01*
G02X1294000Y121461I0J200D01*
G01X1293659Y121802D01*
X1293630Y121830D01*
X1293600Y121904D01*
Y140398D01*
G02X1293800Y140598I200J0D01*
G01X1333115D01*
G03X1333257Y140657I0J200D01*
G01X1336541Y143941D01*
G03X1336600Y144083I-141J142D01*
G01Y150322D01*
G03X1336602Y150500I-8500J185D01*
G03X1336600Y150678I-8502J-7D01*
G01Y161917D01*
G03X1336541Y162059I-200J0D01*
G01X1332857Y165743D01*
G03X1332715Y165802I-142J-141D01*
G01X1294142D01*
G02X1294000Y165861I0J200D01*
G01X1293659Y166202D01*
X1293630Y166230D01*
X1293600Y166304D01*
Y184798D01*
G02X1293800Y184998I200J0D01*
G01X1333515D01*
G03X1333657Y185057I0J200D01*
G01X1337041Y188441D01*
G03X1337100Y188583I-141J142D01*
G01Y194822D01*
G03X1337102Y195000I-8500J185D01*
G03X1337100Y195178I-8502J-7D01*
G01Y207417D01*
G03X1337041Y207559I-200J0D01*
G01X1334457Y210143D01*
G03X1334315Y210202I-142J-141D01*
G01X1294142D01*
G02X1294000Y210261I0J200D01*
G01X1293659Y210602D01*
X1293630Y210630D01*
X1293600Y210704D01*
Y229198D01*
G02X1293800Y229398I200J0D01*
G01X1333415D01*
G03X1333557Y229457I0J200D01*
G01X1337041Y232941D01*
G03X1337100Y233083I-141J142D01*
G01Y251917D01*
G03X1337041Y252059I-200J0D01*
G01X1334557Y254543D01*
G03X1334415Y254602I-142J-141D01*
G01X1294142D01*
G02X1294000Y254661I0J200D01*
G01X1293659Y255002D01*
X1293630Y255030D01*
X1293600Y255104D01*
Y273598D01*
G02X1293800Y273798I200J0D01*
G01X1334315D01*
G03X1334457Y273857I0J200D01*
G01X1337041Y276441D01*
G03X1337100Y276583I-141J142D01*
G01Y296417D01*
G03X1337041Y296559I-200J0D01*
G01X1334659Y298941D01*
G03X1334517Y299000I-142J-141D01*
G01X1319013D01*
G03X1318846Y299002I-173J-7500D01*
G01X1294142D01*
G02X1294000Y299061I0J200D01*
G01X1293659Y299402D01*
X1293630Y299430D01*
X1293600Y299504D01*
Y313417D01*
G02X1293657Y313557I200J0D01*
G01X1294541Y314441D01*
G02X1294543Y314443I142J-140D01*
G02X1294683Y314500I140J-143D01*
G01X1360017D01*
G03X1360159Y314559I0J200D01*
G01X1367441Y321841D01*
G03X1367500Y321983I-141J142D01*
G01Y391317D01*
G02X1367559Y391459I200J0D01*
G01X1399041Y422941D01*
G03X1399100Y423083I-141J142D01*
G01Y531990D01*
G02X1399157Y532130I200J0D01*
G01X1401066Y534039D01*
G02X1401068Y534041I142J-140D01*
G02X1401208Y534098I140J-143D01*
G01X1429104D01*
G03X1429246Y534157I0J200D01*
G01X1443437Y548348D01*
G03X1443496Y548490I-141J142D01*
G01Y593097D01*
G03X1443437Y593239I-200J0D01*
G01X1427425Y609251D01*
G02X1427366Y609393I141J142D01*
G01Y635787D01*
G02X1427423Y635927I200J0D01*
G01X1427937Y636441D01*
G02X1427939Y636443I142J-140D01*
G02X1428079Y636500I140J-143D01*
G01X1519154D01*
G02X1519330Y636394I-1J-200D01*
G03X1529488I5079J2700D01*
G02X1529664Y636500I177J-94D01*
G01X1560417D01*
G03X1560559Y636559I0J200D01*
G01X1561941Y637941D01*
G03X1562000Y638083I-141J142D01*
G01Y664917D01*
G02X1562057Y665057I200J0D01*
G01X1564441Y667441D01*
G02X1564443Y667443I142J-140D01*
G02X1564583Y667500I140J-143D01*
G37*
G36*
G01X1293800Y64600D02*
X1318700D01*
X1318900Y64400D01*
Y59500D01*
X1318700Y59300D01*
X1293800D01*
X1293700Y59400D01*
Y64500D01*
X1293800Y64600D01*
G37*
G36*
G01Y109000D02*
X1318700D01*
X1318900Y108800D01*
Y103900D01*
X1318700Y103700D01*
X1293800D01*
X1293700Y103800D01*
Y108900D01*
X1293800Y109000D01*
G37*
G36*
G01Y153400D02*
X1318700D01*
X1318900Y153200D01*
Y148300D01*
X1318700Y148100D01*
X1293800D01*
X1293700Y148200D01*
Y153300D01*
X1293800Y153400D01*
G37*
G36*
G01Y197800D02*
X1318700D01*
X1318900Y197600D01*
Y192700D01*
X1318700Y192500D01*
X1293800D01*
X1293700Y192600D01*
Y197700D01*
X1293800Y197800D01*
G37*
G36*
G01Y242200D02*
X1318700D01*
X1318900Y242000D01*
Y237100D01*
X1318700Y236900D01*
X1293800D01*
X1293700Y237000D01*
Y242100D01*
X1293800Y242200D01*
G37*
G36*
G01Y286600D02*
X1318700D01*
X1318900Y286400D01*
Y281500D01*
X1318700Y281300D01*
X1293800D01*
X1293700Y281400D01*
Y286500D01*
X1293800Y286600D01*
G37*
G36*
G01X1428447Y668790D02*
X1542860D01*
G02X1543002Y668731I0J-200D01*
G01X1544458Y667275D01*
G02X1544517Y667133I-141J-142D01*
G01Y646707D01*
G02X1544458Y646565I-200J0D01*
G01X1542749Y644856D01*
G02X1542607Y644797I-142J141D01*
G01X1525166D01*
X1525153Y644799D01*
G03X1523665I-744J-5705D01*
G01X1523652Y644797D01*
X1428543D01*
G02X1428401Y644856I0J200D01*
G01X1426504Y646753D01*
G02X1426445Y646895I141J142D01*
G01Y666788D01*
G02X1426504Y666930I200J0D01*
G01X1428305Y668731D01*
G02X1428447Y668790I142J-141D01*
G37*
G36*
G01X1585974Y98204D02*
Y61685D01*
G02X1585915Y61543I-200J0D01*
G01X1584446Y60074D01*
G02X1584304Y60015I-142J141D01*
G01X1570577D01*
G02X1570435Y60074I0J200D01*
G01X1566584Y63925D01*
G02X1566525Y64067I141J142D01*
G01Y98204D01*
Y108917D01*
X1567959Y110351D01*
X1585027D01*
X1585974Y109404D01*
Y98204D01*
G37*
G36*
G01X1637880Y109394D02*
X1652106D01*
X1652300Y109200D01*
Y76000D01*
X1651300Y75000D01*
X1636500D01*
X1635900Y75600D01*
Y85448D01*
X1637532Y87080D01*
Y109046D01*
G02X1637590Y109187I200J0D01*
G01X1637738Y109335D01*
G02X1637880Y109394I142J-141D01*
G37*
G36*
G01X1625640Y113810D02*
X1625629Y113799D01*
G02X1625487Y113740I-142J141D01*
G01X1621653D01*
G02X1621511Y113799I0J200D01*
G01X1620929Y114381D01*
G02X1620870Y114523I141J142D01*
G01Y119757D01*
G02X1620929Y119899I200J0D01*
G01X1621511Y120481D01*
G02X1621653Y120540I142J-141D01*
G01X1625187D01*
G02X1625329Y120481I0J-200D01*
G01X1625611Y120199D01*
G02X1625670Y120057I-141J-142D01*
G01Y113883D01*
X1625640Y113810D01*
G37*
G36*
G01X1627953Y109040D02*
X1630287D01*
G02X1630429Y108981I0J-200D01*
G01X1630911Y108499D01*
G02X1630970Y108357I-141J-142D01*
G01Y99823D01*
G02X1630911Y99681I-200J0D01*
G01X1630529Y99299D01*
G02X1630387Y99240I-142J141D01*
G01X1627653D01*
G02X1627511Y99299I0J200D01*
G01X1627430Y99380D01*
G02X1627372Y99521I142J141D01*
G01Y108459D01*
G02X1627430Y108600I200J0D01*
G01X1627811Y108981D01*
G02X1627953Y109040I142J-141D01*
G37*
G36*
G01X1637101Y115700D02*
Y110699D01*
X1637200Y110600D01*
X1677100D01*
X1677500Y111000D01*
Y120600D01*
X1676500Y121600D01*
X1660300D01*
X1654400Y115700D01*
X1637101D01*
G37*
G36*
G01X1625411Y93799D02*
X1623629Y95581D01*
G02X1623570Y95723I141J142D01*
G01Y108757D01*
G02X1623629Y108899I200J0D01*
G01X1623711Y108981D01*
G02X1623853Y109040I142J-141D01*
G01X1626187D01*
G02X1626329Y108981I0J-200D01*
G01X1626340Y108970D01*
X1626370Y108897D01*
Y98423D01*
G03X1626429Y98281I200J0D01*
G01X1627111Y97599D01*
G03X1627253Y97540I142J141D01*
G01X1630487D01*
G02X1630629Y97481I0J-200D01*
G01X1630811Y97299D01*
G02X1630870Y97157I-141J-142D01*
G01Y94323D01*
G02X1630811Y94181I-200J0D01*
G01X1630429Y93799D01*
G02X1630287Y93740I-142J141D01*
G01X1625553D01*
G02X1625411Y93799I0J200D01*
G37*
G36*
G01X1627157Y120644D02*
X1635957D01*
X1636507Y120094D01*
Y117374D01*
X1636257Y117124D01*
X1627307D01*
X1626817Y117614D01*
Y120304D01*
X1627157Y120644D01*
G37*
G36*
G01X1635213Y109290D02*
X1636330D01*
G02X1636530Y109090I0J-200D01*
G01Y102830D01*
X1636360Y102660D01*
Y91770D01*
X1636278Y91688D01*
Y90178D01*
X1635890Y89790D01*
X1633713D01*
G02X1633571Y89849I0J200D01*
G01X1633089Y90331D01*
G02X1633030Y90473I141J142D01*
G01Y102874D01*
G02X1633089Y103016I200J0D01*
G01X1634771Y104698D01*
G03X1634830Y104840I-141J142D01*
G01Y108907D01*
G02X1634889Y109049I200J0D01*
G01X1635071Y109231D01*
G02X1635213Y109290I142J-141D01*
G37*
G36*
G01X1627053Y138640D02*
X1649800D01*
X1650600Y137840D01*
Y129900D01*
X1650240Y129540D01*
X1640500D01*
X1626833D01*
G02X1626691Y129599I0J200D01*
G01X1626469Y129821D01*
G02X1626410Y129963I141J142D01*
G01Y137997D01*
G02X1626469Y138139I200J0D01*
G01X1626911Y138581D01*
G02X1627053Y138640I142J-141D01*
G37*
G36*
G01X1586483Y667000D02*
X1598243D01*
G02X1598383Y666943I0J-200D01*
G01X1604141Y661185D01*
G02X1604143Y661183I-140J-142D01*
G02X1604200Y661043I-143J-140D01*
G01Y633283D01*
G03X1604259Y633141I200J0D01*
G01X1620341Y617059D01*
G03X1620483Y617000I142J141D01*
G01X1715917D01*
G02X1716057Y616943I0J-200D01*
G01X1726841Y606159D01*
G02X1726843Y606157I-140J-142D01*
G02X1726900Y606017I-143J-140D01*
G01Y526683D01*
G03X1726959Y526541I200J0D01*
G01X1741941Y511559D01*
G03X1742083Y511500I142J141D01*
G01X1859917D01*
G02X1860057Y511443I0J-200D01*
G01X1866941Y504559D01*
G02X1866943Y504557I-140J-142D01*
G02X1867000Y504417I-143J-140D01*
G01Y374543D01*
X1866952Y374425D01*
X1866948Y374411D01*
G03X1866941Y374359I193J-52D01*
G01Y313524D01*
G02X1866882Y313382I-200J0D01*
G01X1865059Y311559D01*
G02X1864917Y311500I-142J141D01*
G01X1855583D01*
G02X1855441Y311559I0J200D01*
G01X1854059Y312941D01*
G02X1854000Y313083I141J142D01*
G01Y314620D01*
G02X1854057Y314760I200J0D01*
G01X1855040Y315743D01*
G02X1855117Y315791I142J-141D01*
G03X1857571Y319213I-1160J3423D01*
G03X1855609Y322427I-3613J0D01*
G02X1855500Y322605I91J178D01*
G01Y325891D01*
G02X1855607Y326068I200J0D01*
G03X1857509Y329213I-1649J3145D01*
G03X1857326Y330338I-3552J0D01*
G01X1857308Y330392D01*
X1857334Y330502D01*
X1857668Y330836D01*
X1857778Y330862D01*
X1857832Y330844D01*
G03X1858957Y330661I1125J3369D01*
G03Y337765I0J3552D01*
G03X1857832Y337582I0J-3552D01*
G01X1857778Y337564D01*
X1857668Y337590D01*
X1857334Y337924D01*
X1857308Y338034D01*
X1857326Y338088D01*
G03X1857509Y339213I-3369J1125D01*
G03X1857326Y340338I-3552J0D01*
G01X1857308Y340392D01*
X1857334Y340502D01*
X1857668Y340836D01*
X1857778Y340862D01*
X1857832Y340844D01*
G03X1858957Y340661I1125J3369D01*
G03Y347765I0J3552D01*
G03X1857832Y347582I0J-3552D01*
G01X1857778Y347564D01*
X1857668Y347590D01*
X1857334Y347924D01*
X1857308Y348034D01*
X1857326Y348088D01*
G03X1857509Y349213I-3369J1125D01*
G03X1853957Y352765I-3552J0D01*
G01X1853956D01*
G03X1851297Y351568I0J-3552D01*
G01X1851283Y351552D01*
X1851233Y351515D01*
X1851216Y351502D01*
X1851161Y351476D01*
G02X1851041Y351460I-85J181D01*
G01X1850771Y351508D01*
X1850734Y351514D01*
X1850688Y351541D01*
G02X1850648Y351572I102J172D01*
G01X1850577Y351643D01*
X1850562Y351684D01*
G03X1843957Y356265I-6605J-2471D01*
G03X1836905Y349213I0J-7052D01*
G03X1841486Y342608I7052J0D01*
G01X1841527Y342593D01*
X1841606Y342514D01*
G02X1841661Y342408I-142J-141D01*
G01X1841710Y342131D01*
Y342130D01*
X1841715Y342108D01*
X1841711Y342073D01*
G02X1841694Y342010I-199J20D01*
G01X1841668Y341954D01*
X1841655Y341937D01*
X1841618Y341887D01*
X1841602Y341873D01*
G03Y336553I2355J-2660D01*
G01X1841618Y336539D01*
X1841655Y336489D01*
X1841668Y336472D01*
X1841694Y336417D01*
G02X1841710Y336297I-181J-85D01*
G01X1841662Y336027D01*
X1841656Y335990D01*
X1841629Y335944D01*
G02X1841598Y335904I-172J102D01*
G01X1841527Y335833D01*
X1841486Y335818D01*
G03X1839140Y324063I2471J-6605D01*
G02X1839203Y323918I-137J-146D01*
G01Y308586D01*
G02X1839144Y308444I-200J0D01*
G01X1835359Y304659D01*
G03X1835300Y304517I141J-142D01*
G01Y263183D01*
G03X1835359Y263041I200J0D01*
G01X1841541Y256859D01*
G03X1841683Y256800I142J141D01*
G01X1866217D01*
G02X1866357Y256743I0J-200D01*
G01X1866882Y256218D01*
G02X1866884Y256216I-140J-142D01*
G02X1866941Y256076I-143J-140D01*
G01Y81069D01*
G02X1866882Y80927I-200J0D01*
G01X1860726Y74771D01*
X1860673D01*
X1858053Y72151D01*
X1858025Y72122D01*
X1857951Y72092D01*
X1740727D01*
G03X1740585Y72033I0J-200D01*
G01X1725088Y56536D01*
G03X1725029Y56394I141J-142D01*
G01Y16138D01*
G02X1724970Y15996I-200J0D01*
G01X1714436Y5462D01*
X1714408Y5433D01*
X1714334Y5403D01*
X1497061D01*
G02X1496881Y5516I0J200D01*
G01X1496732Y5823D01*
G02X1496722Y5972I180J87D01*
G01Y5973D01*
X1496746Y6049D01*
X1496768Y6077D01*
G03X1486759Y15086I-5351J4120D01*
G02X1486694Y15044I-139J144D01*
G01X1486653Y15028D01*
G02X1486580Y15014I-74J186D01*
G01X1486524D01*
X1486319Y15061D01*
X1486317D01*
X1486268Y15073D01*
G02X1486175Y15124I46J195D01*
G01X1486132Y15161D01*
G02X1486095Y15203I130J152D01*
G01X1486062Y15254D01*
X1486054Y15273D01*
G03X1480197Y19290I-5857J-2261D01*
G03X1474055Y14309I0J-6277D01*
G02X1473900Y14154I-196J41D01*
G03X1473124Y13940I1278J-6147D01*
G01X1473107Y13934D01*
X1473083Y13929D01*
G02X1472999Y13931I-37J197D01*
G01X1472975Y13937D01*
X1472953Y13948D01*
X1472871Y13984D01*
G02X1472764Y14079I71J187D01*
G01X1472753Y14100D01*
X1472750Y14108D01*
G03X1470197Y15790I-2553J-1097D01*
G03X1467419Y13012I0J-2778D01*
G03X1469101Y10459I2779J0D01*
G01X1469111Y10455D01*
X1469132Y10444D01*
G02X1469214Y10358I-97J-175D01*
G01X1469216Y10354D01*
X1469277Y10225D01*
X1469281Y10194D01*
X1469286Y10162D01*
X1469273Y10094D01*
X1469268Y10080D01*
G03X1468919Y8017I5929J-2064D01*
G01Y8009D01*
G03X1469261Y5969I6278J4D01*
G01X1469262Y5967D01*
X1469272Y5935D01*
X1469278Y5894D01*
Y5859D01*
G02X1469241Y5743I-200J0D01*
G01X1469058Y5487D01*
X1469030Y5447D01*
X1468944Y5403D01*
X1468162D01*
G02X1467974Y5535I0J200D01*
G01Y10288D01*
G03X1467473Y10790I-502J0D01*
G01X1464158D01*
G02X1463958Y10990I0J200D01*
G01Y14948D01*
G02X1464031Y15102I200J-1D01*
G01X1464034Y15104D01*
X1464281Y15292D01*
G02X1464402Y15333I121J-159D01*
G01X1464444D01*
X1464469Y15326D01*
G03X1465179Y15234I709J2688D01*
G01X1465197D01*
G03Y20790I0J2778D01*
G03X1464464Y20691I2J-2778D01*
G01X1464418Y20678D01*
X1464327Y20696D01*
X1464037Y20918D01*
G02X1463958Y21077I121J159D01*
G01Y30274D01*
G03X1463899Y30416I-200J0D01*
G01X1458034Y36281D01*
G03X1457892Y36340I-142J-141D01*
G01X240423D01*
G03X240281Y36281I0J-200D01*
G01X212559Y8559D01*
X212531Y8530D01*
X212457Y8500D01*
X17583D01*
G02X17441Y8559I0J200D01*
G01X8559Y17441D01*
X8530Y17469D01*
X8500Y17543D01*
Y607917D01*
G02X8557Y608057I200J0D01*
G01X12941Y612441D01*
G02X12943Y612443I142J-140D01*
G02X13083Y612500I140J-143D01*
G01X115917D01*
G02X116057Y612443I0J-200D01*
G01X119441Y609059D01*
G02X119443Y609057I-140J-142D01*
G02X119500Y608917I-143J-140D01*
G01Y164774D01*
X119463Y164656D01*
X119446Y164632D01*
G03Y162368I1653J-1132D01*
G01X119463Y162344D01*
X119500Y162226D01*
Y147116D01*
G02X119485Y147040I-200J0D01*
G01X119440Y146931D01*
X119412Y146903D01*
G03X118838Y145500I1428J-1403D01*
G03X119412Y144096I2004J0D01*
G01X119438Y144069D01*
X119482Y143965D01*
X119498Y143927D01*
Y138260D01*
G03X119499Y138243I1338J70D01*
G01X119500Y138235D01*
Y113129D01*
G03X119559Y112987I200J0D01*
G01X135483Y97063D01*
G03X135625Y97004I142J141D01*
G01X163098D01*
G02X163238Y96947I0J-200D01*
G01X169625Y90560D01*
G02X169627Y90558I-140J-142D01*
G02X169684Y90418I-143J-140D01*
G01Y64070D01*
G03X169743Y63928I200J0D01*
G01X169796Y63875D01*
G03X169938Y63816I142J141D01*
G01X189115D01*
G03X189257Y63875I0J200D01*
G01X190935Y65553D01*
G03X190994Y65695I-141J142D01*
G01Y99370D01*
G02X191051Y99510I200J0D01*
G01X191482Y99941D01*
G02X191484Y99943I142J-140D01*
G02X191624Y100000I140J-143D01*
G01X220517D01*
G03X220659Y100059I0J200D01*
G01X222541Y101941D01*
G03X222600Y102083I-141J142D01*
G01Y119917D01*
G02X222657Y120057I200J0D01*
G01X223541Y120941D01*
G02X223543Y120943I142J-140D01*
G02X223683Y121000I140J-143D01*
G01X271438D01*
G02X271578Y120943I0J-200D01*
G01X289233Y103288D01*
G03X289235Y103286I142J140D01*
G01X292661Y99943D01*
G02X292663Y99941I-140J-142D01*
G01X307995Y84609D01*
G03X308137Y84550I142J141D01*
G01X348604D01*
X388195Y44959D01*
X389669D01*
G03X389811Y44900I142J141D01*
G01X476429D01*
G02X476569Y44843I0J-200D01*
G01X482554Y38858D01*
G03X482696Y38799I142J141D01*
G01X564672D01*
G03X564814Y38858I0J200D01*
G01X571897Y45941D01*
G02X571899Y45943I142J-140D01*
G02X572039Y46000I140J-143D01*
G01X630321D01*
G03X630463Y46059I0J200D01*
G01X641576Y57172D01*
G03X641635Y57314I-141J142D01*
G01Y99795D01*
G02X641692Y99935I200J0D01*
G01X643043Y101286D01*
G02X643045Y101288I142J-140D01*
G02X643185Y101345I140J-143D01*
G01X811042D01*
G02X811307Y100646I-1J-400D01*
G03X805835Y88484I10780J-12162D01*
G03X838339I16252J0D01*
G03X831964Y101390I-16253J-1D01*
G01X831953Y101398D01*
X831907Y101444D01*
X831891Y101474D01*
X831876Y101505D01*
G02X831940Y101753I181J86D01*
G01X831968Y101773D01*
X831996Y101787D01*
X832007Y101794D01*
G03X832045Y101823I-101J172D01*
G01X840179Y109957D01*
G03X840238Y110099I-141J142D01*
G01Y210116D01*
G03X840179Y210258I-200J0D01*
G01X833496Y216941D01*
G03X833354Y217000I-142J-141D01*
G01X720789D01*
X720715Y217030D01*
X720687Y217059D01*
X718343Y219403D01*
G02X718284Y219545I141J142D01*
G01Y233201D01*
G02X718341Y233341I200J0D01*
G01X727191Y242191D01*
G02X727193Y242193I142J-140D01*
G02X727333Y242250I140J-143D01*
G01X743268D01*
X746898Y245880D01*
Y318235D01*
X729035Y336098D01*
X720056D01*
G03X719914Y336157I-142J-141D01*
G01X683740D01*
G03X683598Y336098I0J-200D01*
G01X681559Y334059D01*
G02X681417Y334000I-142J141D01*
G01X674700D01*
X674626Y334030D01*
X674598Y334059D01*
X673851Y334806D01*
Y354342D01*
X671776Y356417D01*
X626447D01*
X612030Y342000D01*
X590583D01*
G03X590441Y341941I0J-200D01*
G01X584716Y336216D01*
X584688Y336187D01*
X584614Y336157D01*
X483541D01*
X483487Y336172D01*
X483464Y336187D01*
G03X483361Y336216I-104J-171D01*
G01X414237D01*
G03X414095Y336157I0J-200D01*
G01X403775Y325837D01*
X403747Y325808D01*
X403673Y325778D01*
X384869D01*
G02X384727Y325837I0J200D01*
G01X347659Y362905D01*
X347630Y362933D01*
X347600Y363007D01*
Y396417D01*
G02X347657Y396557I200J0D01*
G01X350041Y398941D01*
G02X350043Y398943I142J-140D01*
G02X350183Y399000I140J-143D01*
G01X766206D01*
X766324Y398952D01*
X766338Y398948D01*
G03X766390Y398941I52J193D01*
G01X1311159D01*
X1311168Y398932D01*
X1352987D01*
G02X1353127Y398875I0J-200D01*
G01X1356114Y395888D01*
G02X1356116Y395886I-140J-142D01*
G02X1356173Y395746I-143J-140D01*
G01Y337116D01*
X1356143Y337042D01*
X1356114Y337014D01*
X1346159Y327059D01*
G02X1346017Y327000I-142J141D01*
G01X1295643D01*
X1295569Y327030D01*
X1295541Y327059D01*
X1269078Y353522D01*
G03X1268936Y353581I-142J-141D01*
G01X1192002D01*
G02X1191860Y353640I0J200D01*
G01X1182500Y363000D01*
X1136763D01*
X1135263Y364500D01*
X1135189Y364530D01*
X1135161Y364559D01*
X1133559Y366161D01*
G02X1133500Y366303I141J142D01*
G01Y366923D01*
G03X1133503Y367000I-1500J97D01*
G01Y367001D01*
G03X1130497I-1503J-1D01*
G01Y367000D01*
G03X1130500Y366923I1503J20D01*
G01Y366043D01*
X1130470Y365969D01*
X1130441Y365941D01*
X1127099Y362599D01*
G02X1126957Y362540I-142J141D01*
G01X1091423D01*
G03X1091281Y362481I0J-200D01*
G01X1082440Y353640D01*
G02X1082298Y353581I-142J141D01*
G01X1064984D01*
G03X1064842Y353522I0J-200D01*
G01X1063813Y352493D01*
G03X1063306Y352503I-510J-12993D01*
G01X1063300D01*
G03X1050297Y339500I0J-13003D01*
G01Y339494D01*
G03X1050307Y338987I13003J3D01*
G01X1026252Y314932D01*
G02X1026211Y314900I-143J140D01*
G01X1026178Y314881D01*
X1026145Y314874D01*
G03X1026041Y314818I39J-196D01*
G01X1014059Y302836D01*
G03X1014000Y302694I141J-142D01*
G01Y217943D01*
X1013970Y217869D01*
X1013941Y217841D01*
X1013218Y217118D01*
G02X1013076Y217059I-142J141D01*
G01X944642D01*
G03X944538Y217030I0J-200D01*
G01X944537Y217029D01*
G02X944433Y217000I-104J171D01*
G01X900325D01*
G03X900183Y216941I0J-200D01*
G01X892816Y209574D01*
G03X892757Y209432I141J-142D01*
G01Y107581D01*
G03X892816Y107439I200J0D01*
G01X897862Y102393D01*
G03X898004Y102334I142J141D01*
G01X930380D01*
G02X930616Y101611I0J-400D01*
G03X923945Y88484I9580J-13127D01*
G03X956449I16252J0D01*
G03X949778Y101611I-16251J0D01*
G02X950014Y102334I236J323D01*
G01X1086617D01*
G02X1086757Y102277I0J-200D01*
G01X1088108Y100926D01*
G02X1088110Y100924I-140J-142D01*
G02X1088167Y100784I-143J-140D01*
G01Y53516D01*
G03X1088226Y53374I200J0D01*
G01X1096541Y45059D01*
G03X1096683Y45000I142J141D01*
G01X1191117D01*
G02X1191257Y44943I0J-200D01*
G01X1195641Y40559D01*
G03X1195783Y40500I142J141D01*
G01X1282317D01*
G03X1282459Y40559I0J200D01*
G01X1286841Y44941D01*
G02X1286843Y44943I142J-140D01*
G02X1286983Y45000I140J-143D01*
G01X1320817D01*
G03X1320959Y45059I0J200D01*
G01X1335960Y60060D01*
X1397648D01*
X1406088Y68500D01*
G03X1406230Y68559I0J200D01*
G01X1454506Y116835D01*
G02X1454508Y116837I142J-140D01*
G02X1454648Y116894I140J-143D01*
G01X1512615D01*
G02X1512755Y116837I0J-200D01*
G01X1515587Y114005D01*
G02X1515589Y114003I-140J-142D01*
G02X1515646Y113863I-143J-140D01*
G01Y100248D01*
G03X1515705Y100106I200J0D01*
G01X1517049Y98762D01*
X1517075Y98715D01*
X1517082Y98688D01*
G03X1517135Y98593I194J46D01*
G01X1521759Y93969D01*
G03X1521901Y93910I142J141D01*
G01X1558824D01*
G02X1559024Y93710I0J-200D01*
G01Y67658D01*
X1559023Y67650D01*
G03X1558998Y67000I8477J-652D01*
G03X1559023Y66350I8502J2D01*
G01X1559024Y66342D01*
Y64066D01*
G03X1561282Y58618I7701J0D01*
G01X1565128Y54772D01*
G03X1570576Y52514I5448J5443D01*
G01X1584305D01*
G03X1589753Y54772I0J7701D01*
G01X1591217Y56236D01*
G03X1593476Y61684I-5443J5449D01*
G01Y92593D01*
G02X1593533Y92733I200J0D01*
G01X1594541Y93741D01*
G02X1594543Y93743I142J-140D01*
G02X1594683Y93800I140J-143D01*
G01X1610917D01*
G02X1611057Y93743I0J-200D01*
G01X1621041Y83759D01*
G03X1621183Y83700I142J141D01*
G01X1629817D01*
G02X1629957Y83643I0J-200D01*
G01X1630441Y83159D01*
G02X1630443Y83157I-140J-142D01*
G02X1630500Y83017I-143J-140D01*
G01Y66383D01*
G03X1630559Y66241I200J0D01*
G01X1633841Y62959D01*
G03X1633983Y62900I142J141D01*
G01X1653217D01*
G03X1653359Y62959I0J200D01*
G01X1660741Y70341D01*
G03X1660800Y70483I-141J142D01*
G01Y92217D01*
G02X1660857Y92357I200J0D01*
G01X1669241Y100741D01*
G02X1669243Y100743I142J-140D01*
G02X1669383Y100800I140J-143D01*
G01X1677017D01*
G02X1677157Y100743I0J-200D01*
G01X1678141Y99759D01*
G02X1678143Y99757I-140J-142D01*
G02X1678200Y99617I-143J-140D01*
G01Y84383D01*
G03X1678259Y84241I200J0D01*
G01X1687941Y74559D01*
G03X1688083Y74500I142J141D01*
G01X1700017D01*
G03X1700159Y74559I0J200D01*
G01X1704541Y78941D01*
G03X1704600Y79083I-141J142D01*
G01Y89800D01*
G02X1704800Y90000I200J0D01*
G01X1707517D01*
G02X1707657Y89943I0J-200D01*
G01X1710241Y87358D01*
G02X1710243Y87356I-140J-142D01*
G02X1710300Y87216I-143J-140D01*
G01Y83683D01*
G03X1710359Y83541I200J0D01*
G01X1711341Y82559D01*
G03X1711483Y82500I142J141D01*
G01X1722517D01*
G03X1722659Y82559I0J200D01*
G01X1726041Y85941D01*
G03X1726100Y86083I-141J142D01*
G01Y104917D01*
G02X1726157Y105057I200J0D01*
G01X1726541Y105441D01*
G02X1726543Y105443I142J-140D01*
G02X1726683Y105500I140J-143D01*
G01X1738517D01*
G02X1738657Y105443I0J-200D01*
G01X1745291Y98809D01*
G03X1745433Y98750I142J141D01*
G01X1772533D01*
G03X1772675Y98809I0J200D01*
G01X1773354Y99488D01*
X1773417Y99518D01*
X1773452Y99521D01*
G03X1777954Y104023I-477J4979D01*
G01X1777957Y104058D01*
X1777987Y104121D01*
X1779307Y105441D01*
G03X1779366Y105583I-141J142D01*
G01Y170783D01*
G02X1779423Y170923I200J0D01*
G01X1792941Y184441D01*
G03X1793000Y184583I-141J142D01*
G01Y209417D01*
G03X1792941Y209559I-200J0D01*
G01X1790159Y212341D01*
G03X1790017Y212400I-142J-141D01*
G01X1660215D01*
G02X1660073Y212459I0J200D01*
G01X1660066Y212466D01*
G03X1658533Y213504I-3465J-3467D01*
G02X1658471Y213546I79J184D01*
G01X1647059Y224958D01*
X1647030Y224986D01*
X1647000Y225060D01*
Y587917D01*
G03X1646941Y588059I-200J0D01*
G01X1636059Y598941D01*
G03X1635917Y599000I-142J-141D01*
G01X1586743D01*
X1586669Y599030D01*
X1586641Y599059D01*
X1586159Y599541D01*
X1586130Y599569D01*
X1586100Y599643D01*
Y666617D01*
G02X1586157Y666757I200J0D01*
G01X1586341Y666941D01*
G02X1586343Y666943I142J-140D01*
G02X1586483Y667000I140J-143D01*
G37*
%LPC*%
G75*
G36*
G01X162784Y233502D02*
G02X163285Y234002I501J-1D01*
G01X170285D01*
G02X170786Y233500I-1J-502D01*
G01Y226498D01*
G02X170285Y225998I-501J1D01*
G01X163285D01*
G02X162784Y226500I1J502D01*
G01Y233502D01*
G37*
G36*
G01X239784D02*
G02X240285Y234002I501J-1D01*
G01X247285D01*
G02X247786Y233500I-1J-502D01*
G01Y226498D01*
G02X247285Y225998I-501J1D01*
G01X240285D01*
G02X239784Y226500I1J502D01*
G01Y233502D01*
G37*
G36*
G01X162784Y313502D02*
G02X163285Y314002I501J-1D01*
G01X170285D01*
G02X170786Y313500I-1J-502D01*
G01Y306498D01*
G02X170285Y305998I-501J1D01*
G01X163285D01*
G02X162784Y306500I1J502D01*
G01Y313502D01*
G37*
G36*
G01X239784D02*
G02X240285Y314002I501J-1D01*
G01X247285D01*
G02X247786Y313500I-1J-502D01*
G01Y306498D01*
G02X247285Y305998I-501J1D01*
G01X240285D01*
G02X239784Y306500I1J502D01*
G01Y313502D01*
G37*
G36*
G01X162784Y393502D02*
G02X163285Y394002I501J-1D01*
G01X170285D01*
G02X170786Y393500I-1J-502D01*
G01Y386498D01*
G02X170285Y385998I-501J1D01*
G01X163285D01*
G02X162784Y386500I1J502D01*
G01Y393502D01*
G37*
G36*
G01X239784D02*
G02X240285Y394002I501J-1D01*
G01X247285D01*
G02X247786Y393500I-1J-502D01*
G01Y386498D01*
G02X247285Y385998I-501J1D01*
G01X240285D01*
G02X239784Y386500I1J502D01*
G01Y393502D01*
G37*
G36*
G01X162784Y473502D02*
G02X163285Y474002I501J-1D01*
G01X170285D01*
G02X170786Y473500I-1J-502D01*
G01Y466498D01*
G02X170285Y465998I-501J1D01*
G01X163285D01*
G02X162784Y466500I1J502D01*
G01Y473502D01*
G37*
G36*
G01X239784D02*
G02X240285Y474002I501J-1D01*
G01X247285D01*
G02X247786Y473500I-1J-502D01*
G01Y466498D01*
G02X247285Y465998I-501J1D01*
G01X240285D01*
G02X239784Y466500I1J502D01*
G01Y473502D01*
G37*
G36*
G01X162784Y553502D02*
G02X163285Y554002I501J-1D01*
G01X170285D01*
G02X170786Y553500I-1J-502D01*
G01Y546498D01*
G02X170285Y545998I-501J1D01*
G01X163285D01*
G02X162784Y546500I1J502D01*
G01Y553502D01*
G37*
G36*
G01X239784D02*
G02X240285Y554002I501J-1D01*
G01X247285D01*
G02X247786Y553500I-1J-502D01*
G01Y546498D01*
G02X247285Y545998I-501J1D01*
G01X240285D01*
G02X239784Y546500I1J502D01*
G01Y553502D01*
G37*
G36*
G01X1484498Y233500D02*
G02X1485000Y234002I502J0D01*
G01X1492000D01*
G02X1492502Y233500I0J-502D01*
G01Y226500D01*
G02X1492000Y225998I-502J0D01*
G01X1485000D01*
G02X1484498Y226500I0J502D01*
G01Y233500D01*
G37*
G36*
G01X1561498D02*
G02X1562000Y234002I502J0D01*
G01X1569000D01*
G02X1569502Y233500I0J-502D01*
G01Y226500D01*
G02X1569000Y225998I-502J0D01*
G01X1562000D01*
G02X1561498Y226500I0J502D01*
G01Y233500D01*
G37*
G36*
G01X1484498Y313500D02*
G02X1485000Y314002I502J0D01*
G01X1492000D01*
G02X1492502Y313500I0J-502D01*
G01Y306500D01*
G02X1492000Y305998I-502J0D01*
G01X1485000D01*
G02X1484498Y306500I0J502D01*
G01Y313500D01*
G37*
G36*
G01X1561498D02*
G02X1562000Y314002I502J0D01*
G01X1569000D01*
G02X1569502Y313500I0J-502D01*
G01Y306500D01*
G02X1569000Y305998I-502J0D01*
G01X1562000D01*
G02X1561498Y306500I0J502D01*
G01Y313500D01*
G37*
G36*
G01X1484498Y393500D02*
G02X1485000Y394002I502J0D01*
G01X1492000D01*
G02X1492502Y393500I0J-502D01*
G01Y386500D01*
G02X1492000Y385998I-502J0D01*
G01X1485000D01*
G02X1484498Y386500I0J502D01*
G01Y393500D01*
G37*
G36*
G01X1561498D02*
G02X1562000Y394002I502J0D01*
G01X1569000D01*
G02X1569502Y393500I0J-502D01*
G01Y386500D01*
G02X1569000Y385998I-502J0D01*
G01X1562000D01*
G02X1561498Y386500I0J502D01*
G01Y393500D01*
G37*
G36*
G01X1484498Y473500D02*
G02X1485000Y474002I502J0D01*
G01X1492000D01*
G02X1492502Y473500I0J-502D01*
G01Y466500D01*
G02X1492000Y465998I-502J0D01*
G01X1485000D01*
G02X1484498Y466500I0J502D01*
G01Y473500D01*
G37*
G36*
G01X1561498D02*
G02X1562000Y474002I502J0D01*
G01X1569000D01*
G02X1569502Y473500I0J-502D01*
G01Y466500D01*
G02X1569000Y465998I-502J0D01*
G01X1562000D01*
G02X1561498Y466500I0J502D01*
G01Y473500D01*
G37*
G36*
G01X1484498Y553500D02*
G02X1485000Y554002I502J0D01*
G01X1492000D01*
G02X1492502Y553500I0J-502D01*
G01Y546500D01*
G02X1492000Y545998I-502J0D01*
G01X1485000D01*
G02X1484498Y546500I0J502D01*
G01Y553500D01*
G37*
G36*
G01X1561498D02*
G02X1562000Y554002I502J0D01*
G01X1569000D01*
G02X1569502Y553500I0J-502D01*
G01Y546500D01*
G02X1569000Y545998I-502J0D01*
G01X1562000D01*
G02X1561498Y546500I0J502D01*
G01Y553500D01*
G37*
G36*
G01X315639Y73837D02*
G02X315497Y74475I1362J638D01*
G02X318503I1503J0D01*
G02X318361Y73837I-1504J0D01*
G01X318342Y73796D01*
Y73118D01*
X318355Y73068D01*
X318369Y73045D01*
G02X318487Y72601I-776J-444D01*
G01Y71732D01*
G02X318428Y71590I-200J0D01*
G01X318400Y71562D01*
X318378Y71553D01*
X318321Y71531D01*
X318251Y71429D01*
Y69646D01*
G03X318422Y69468I199J20D01*
G01X318487D01*
Y68413D01*
G02X318390Y68009I-892J0D01*
G01X318368Y67966D01*
Y67915D01*
X318359Y67901D01*
X318351Y67875D01*
G03X318342Y67816I191J-59D01*
G01Y65179D01*
X318361Y65138D01*
G02X318503Y64500I-1362J-638D01*
G02X315497I-1503J0D01*
G02X315639Y65138I1504J0D01*
G01X315658Y65179D01*
Y67882D01*
X315645Y67932D01*
X315631Y67955D01*
G02X315513Y68399I776J444D01*
G01Y69268D01*
G02X315572Y69410I200J0D01*
G01X315600Y69438D01*
X315622Y69447D01*
X315679Y69469D01*
X315749Y69571D01*
Y71354D01*
G03X315578Y71532I-199J-20D01*
G01X315513D01*
Y72587D01*
G02X315610Y72991I892J0D01*
G01X315632Y73034D01*
Y73085D01*
X315641Y73099D01*
X315649Y73125D01*
G03X315658Y73184I-191J59D01*
G01Y73796D01*
X315639Y73837D01*
G37*
G36*
G01X320139D02*
G02X319997Y74475I1362J638D01*
G02X323003I1503J0D01*
G02X322861Y73837I-1504J0D01*
G01X322842Y73796D01*
Y73118D01*
X322855Y73068D01*
X322869Y73045D01*
G02X322987Y72601I-776J-444D01*
G01Y71732D01*
G02X322928Y71590I-200J0D01*
G01X322900Y71562D01*
X322878Y71553D01*
X322821Y71531D01*
X322751Y71429D01*
Y69646D01*
G03X322922Y69468I199J20D01*
G01X322987D01*
Y68413D01*
G02X322890Y68009I-892J0D01*
G01X322868Y67966D01*
Y67915D01*
X322859Y67901D01*
X322851Y67875D01*
G03X322842Y67816I191J-59D01*
G01Y67179D01*
X322861Y67138D01*
G02X323003Y66500I-1362J-638D01*
G02X319997I-1503J0D01*
G02X320139Y67138I1504J0D01*
G01X320158Y67179D01*
Y67882D01*
X320145Y67932D01*
X320131Y67955D01*
G02X320013Y68399I776J444D01*
G01Y69268D01*
G02X320072Y69410I200J0D01*
G01X320100Y69438D01*
X320122Y69447D01*
X320179Y69469D01*
X320249Y69571D01*
Y71354D01*
G03X320078Y71532I-199J-20D01*
G01X320013D01*
Y72587D01*
G02X320110Y72991I892J0D01*
G01X320132Y73034D01*
Y73085D01*
X320141Y73099D01*
X320149Y73125D01*
G03X320158Y73184I-191J59D01*
G01Y73796D01*
X320139Y73837D01*
G37*
G36*
G01X324639Y73838D02*
G02X324497Y74476I1362J638D01*
G02X327503I1503J0D01*
G02X327361Y73838I-1504J0D01*
G01X327342Y73797D01*
Y73118D01*
X327355Y73068D01*
X327369Y73045D01*
G02X327487Y72601I-776J-444D01*
G01Y71732D01*
G02X327428Y71590I-200J0D01*
G01X327400Y71562D01*
X327378Y71553D01*
X327321Y71531D01*
X327251Y71429D01*
Y69646D01*
G03X327422Y69468I199J20D01*
G01X327487D01*
Y68413D01*
G02X327390Y68009I-892J0D01*
G01X327368Y67966D01*
Y67915D01*
X327359Y67901D01*
X327351Y67875D01*
G03X327342Y67816I191J-59D01*
G01Y64899D01*
X327341Y64890D01*
Y64427D01*
G02X327282Y64286I-200J1D01*
G01X327132Y64136D01*
X327102Y64061D01*
X327103Y64021D01*
G02Y64000I-2003J-11D01*
G02X323097I-2003J0D01*
G02X324516Y65916I2003J0D01*
G01X324580Y65935D01*
X324658Y66041D01*
Y67882D01*
X324645Y67932D01*
X324631Y67955D01*
G02X324513Y68399I776J444D01*
G01Y69268D01*
G02X324572Y69410I200J0D01*
G01X324600Y69438D01*
X324622Y69447D01*
X324679Y69469D01*
X324749Y69571D01*
Y71354D01*
G03X324578Y71532I-199J-20D01*
G01X324513D01*
Y72587D01*
G02X324610Y72991I892J0D01*
G01X324632Y73034D01*
Y73085D01*
X324641Y73099D01*
X324649Y73125D01*
G03X324658Y73184I-191J59D01*
G01Y73797D01*
X324639Y73838D01*
G37*
G36*
G01X1502367Y73839D02*
G02X1502225Y74477I1362J638D01*
G02X1505231I1503J0D01*
G02X1505089Y73839I-1504J0D01*
G01X1505070Y73799D01*
Y73105D01*
X1505083Y73054D01*
X1505097Y73031D01*
G02X1505215Y72588I-774J-443D01*
G01Y71733D01*
G02X1505015Y71533I-200J0D01*
G01X1504979D01*
Y69669D01*
G03X1505179Y69469I200J0D01*
G01X1505215D01*
Y69419D01*
G03X1505274Y69277I200J0D01*
G01X1506049Y68503D01*
G02X1506084Y68467I-945J-954D01*
G01X1506086Y68464D01*
X1506382Y68168D01*
G02X1506441Y68027I-141J-142D01*
G01Y67602D01*
G02X1506442Y67554I-1341J-52D01*
G01Y65178D01*
X1506461Y65138D01*
G02X1506603Y64500I-1362J-638D01*
G02X1503597I-1503J0D01*
G02X1503739Y65138I1504J0D01*
G01X1503758Y65178D01*
Y66916D01*
G03X1503701Y67056I-200J0D01*
G01X1503293Y67464D01*
G03X1503151Y67523I-142J-141D01*
G01X1503139D01*
G02X1502241Y68414I-6J892D01*
G01Y69269D01*
G02X1502441Y69469I200J0D01*
G01X1502477D01*
Y71354D01*
G03X1502298Y71533I-199J-20D01*
G01X1502241D01*
Y72588D01*
G02X1502359Y73031I892J0D01*
G01X1502373Y73054D01*
X1502386Y73105D01*
Y73799D01*
X1502367Y73839D01*
G37*
G36*
G01X328159Y72075D02*
Y74476D01*
G02X332841I2341J0D01*
G01Y72074D01*
G02X332377Y70677I-2340J2D01*
G01X332357Y70651D01*
X332337Y70589D01*
Y70411D01*
X332357Y70349D01*
X332377Y70323D01*
G02X332841Y68925I-1876J-1399D01*
G01Y66353D01*
G03X332900Y66211I200J0D01*
G01X333309Y65802D01*
Y65801D01*
X334155Y64955D01*
G02X334841Y63300I-1655J-1656D01*
G02X332500Y60959I-2341J0D01*
G02X330845Y61645I1J2341D01*
G01X328218Y64272D01*
G02X328159Y64413I141J142D01*
G01Y68926D01*
G02X328623Y70323I2340J-2D01*
G01X328643Y70349D01*
X328663Y70411D01*
Y70589D01*
X328643Y70651D01*
X328623Y70677D01*
G02X328159Y72075I1876J1399D01*
G37*
G36*
G01X1496886Y72076D02*
Y74500D01*
G02X1501570I2342J0D01*
G01Y72076D01*
G02X1501066Y70625I-2341J0D01*
G03Y70377I157J-124D01*
G02X1501570Y68926I-1837J-1451D01*
G01Y64548D01*
G02X1501569Y64482I-2342J2D01*
G01Y63661D01*
G02X1501510Y63520I-200J1D01*
G01X1500928Y62938D01*
G02X1500884Y62892I-1714J1595D01*
G01X1499836Y61844D01*
G02X1498180Y61158I-1656J1656D01*
G02X1495838Y63500I0J2342D01*
G02X1496524Y65156I2342J0D01*
G01X1496827Y65458D01*
G03X1496886Y65600I-141J142D01*
G01Y68926D01*
G02X1497390Y70377I2341J0D01*
G03Y70625I-157J124D01*
G02X1496886Y72076I1837J1451D01*
G37*
G36*
G01X1488840Y79544D02*
G02X1488497Y80500I1161J956D01*
G02X1490000Y82003I1503J0D01*
G02X1491481Y80754I0J-1503D01*
G03X1491487Y80736I192J54D01*
G02X1491570Y80272I-1259J-465D01*
G01Y73105D01*
X1491583Y73054D01*
X1491597Y73031D01*
G02X1491715Y72588I-774J-443D01*
G01Y71733D01*
G02X1491515Y71533I-200J0D01*
G01X1491479D01*
Y69648D01*
G03X1491658Y69469I199J20D01*
G01X1491715D01*
Y68414D01*
G02X1491597Y67971I-892J0D01*
G01X1491583Y67948D01*
X1491570Y67897D01*
Y67178D01*
X1491589Y67138D01*
G02X1491731Y66500I-1362J-638D01*
G02X1488725I-1503J0D01*
G02X1488867Y67138I1504J0D01*
G01X1488886Y67178D01*
Y67897D01*
X1488873Y67948D01*
X1488859Y67971D01*
G02X1488741Y68414I774J443D01*
G01Y69269D01*
G02X1488941Y69469I200J0D01*
G01X1488977D01*
Y71354D01*
G03X1488798Y71533I-199J-20D01*
G01X1488741D01*
Y72588D01*
G02X1488859Y73031I892J0D01*
G01X1488873Y73054D01*
X1488886Y73105D01*
Y79417D01*
G03X1488840Y79544I-200J-1D01*
G37*
G36*
G01X1493367Y82865D02*
G02X1493226Y83500I1361J635D01*
G02X1496230I1502J0D01*
G02X1496089Y82865I-1502J0D01*
G01X1496070Y82824D01*
Y73105D01*
X1496083Y73054D01*
X1496097Y73031D01*
G02X1496215Y72588I-774J-443D01*
G01Y71733D01*
G02X1496015Y71533I-200J0D01*
G01X1495979D01*
Y69648D01*
G03X1496158Y69469I199J20D01*
G01X1496215D01*
Y68414D01*
G02X1496097Y67971I-892J0D01*
G01X1496083Y67948D01*
X1496070Y67897D01*
Y67178D01*
X1496089Y67138D01*
G02X1496231Y66500I-1362J-638D01*
G02X1493225I-1503J0D01*
G02X1493367Y67138I1504J0D01*
G01X1493386Y67178D01*
Y67897D01*
X1493373Y67948D01*
X1493359Y67971D01*
G02X1493241Y68414I774J443D01*
G01Y69269D01*
G02X1493441Y69469I200J0D01*
G01X1493477D01*
Y71354D01*
G03X1493298Y71533I-199J-20D01*
G01X1493241D01*
Y72588D01*
G02X1493359Y73031I892J0D01*
G01X1493373Y73054D01*
X1493386Y73105D01*
Y82824D01*
X1493367Y82865D01*
G37*
G36*
G01X1845187Y219782D02*
G02X1857758Y220600I6270J651D01*
G02Y220597I-200J-1D01*
G01Y220562D01*
G02X1845196Y219722I-6301J-127D01*
G01Y219727D01*
X1845187Y219782D01*
G37*
G36*
G01X822098Y365500D02*
G02X822600Y366002I502J0D01*
G01X829200D01*
G02X829702Y365500I0J-502D01*
G01Y358900D01*
G02X829200Y358398I-502J0D01*
G01X822600D01*
G02X822098Y358900I0J502D01*
G01Y360658D01*
G03X821898Y360858I-200J0D01*
G01X810973D01*
G03X810830Y360798I0J-200D01*
G02X809400Y360198I-1430J1404D01*
G02Y364202I0J2002D01*
G02X810830Y363602I0J-2004D01*
G03X810973Y363542I143J140D01*
G01X821898D01*
G03X822098Y363742I0J200D01*
G01Y365500D01*
G37*
G36*
G01X903098D02*
G02X903600Y366002I502J0D01*
G01X910200D01*
G02X910702Y365500I0J-502D01*
G01Y363742D01*
G03X910902Y363542I200J0D01*
G01X921527D01*
G03X921670Y363602I0J200D01*
G02X923100Y364202I1430J-1404D01*
G02Y360198I0J-2002D01*
G02X921670Y360798I0J2004D01*
G03X921527Y360858I-143J-140D01*
G01X910902D01*
G03X910702Y360658I0J-200D01*
G01Y358900D01*
G02X910200Y358398I-502J0D01*
G01X903600D01*
G02X903098Y358900I0J502D01*
G01Y365500D01*
G37*
G36*
G01X876815Y364072D02*
G02X876673Y364709I1360J637D01*
G02X879677I1502J0D01*
G02X879535Y364072I-1502J0D01*
G01X879516Y364031D01*
Y362954D01*
G03X879527Y362889I200J0D01*
G02X879576Y362593I-841J-291D01*
G01Y361409D01*
G02X878687Y360514I-890J-5D01*
G01X877834D01*
G02X877652Y360632I0J199D01*
G01X877627Y360686D01*
X877528Y360750D01*
X875766D01*
G03X875566Y360550I0J-200D01*
G01Y360514D01*
X874513D01*
G02X873865Y360795I1J890D01*
G03X873720Y360858I-146J-137D01*
G01X870092D01*
G03X869908Y360735I1J-200D01*
G02X866400Y358398I-3508J1464D01*
G02Y366002I0J3802D01*
G02X869908Y363665I0J-3801D01*
G03X870092Y363542I185J77D01*
G01X874825D01*
G02X875183Y363493I-1J-1342D01*
G01X875210Y363486D01*
X875366D01*
G02X875508Y363427I0J-200D01*
G01X875536Y363399D01*
X875545Y363377D01*
X875567Y363320D01*
X875669Y363250D01*
X876634D01*
G03X876834Y363450I0J200D01*
G01Y364031D01*
X876815Y364072D01*
G37*
G36*
G01X862598Y385500D02*
G02X863100Y386002I502J0D01*
G01X869700D01*
G02X870202Y385500I0J-502D01*
G01Y383742D01*
G03X870402Y383542I200J0D01*
G01X874825D01*
G02X875183Y383493I-1J-1342D01*
G01X875210Y383486D01*
X875366D01*
G02X875508Y383427I0J-200D01*
G01X875536Y383399D01*
X875545Y383377D01*
X875567Y383320D01*
X875669Y383250D01*
X877434D01*
G03X877634Y383450I0J200D01*
G01Y383486D01*
X878687D01*
G02X879576Y382591I-1J-890D01*
G01Y381407D01*
G02X879527Y381111I-890J-5D01*
G03X879516Y381046I189J-65D01*
G01Y374778D01*
X879535Y374737D01*
G02X879677Y374100I-1360J-637D01*
G02X876673I-1502J0D01*
G02X876815Y374737I1502J0D01*
G01X876834Y374778D01*
Y380550D01*
G03X876634Y380750I-200J0D01*
G01X875766D01*
G03X875566Y380550I0J-200D01*
G01Y380514D01*
X874513D01*
G02X873865Y380795I1J890D01*
G03X873720Y380858I-146J-137D01*
G01X870402D01*
G03X870202Y380658I0J-200D01*
G01Y378900D01*
G02X869700Y378398I-502J0D01*
G01X863100D01*
G02X862598Y378900I0J502D01*
G01Y385500D01*
G37*
G36*
G01X1746941Y421441D02*
G02X1747083Y421500I142J-141D01*
G01X1770917D01*
G02X1771059Y421441I0J-200D01*
G01X1780441Y412059D01*
G03X1780583Y412000I142J141D01*
G01X1788326D01*
G02X1788468Y411941I0J-200D01*
G01X1791378Y409031D01*
G02X1791437Y408889I-141J-142D01*
G01Y384476D01*
G02X1791378Y384334I-200J0D01*
G01X1788399Y381355D01*
G02X1788257Y381296I-142J141D01*
G01X1771958D01*
X1771884Y381266D01*
X1771856Y381237D01*
X1770659Y380040D01*
G03X1770600Y379898I141J-142D01*
G01Y360083D01*
G03X1770659Y359941I200J0D01*
G01X1771041Y359559D01*
X1771069Y359530D01*
X1771143Y359500D01*
X1782797D01*
G02X1782939Y359441I0J-200D01*
G01X1800143Y342237D01*
G02X1800202Y342095I-141J-142D01*
G01Y246685D01*
G02X1800143Y246543I-200J0D01*
G01X1798129Y244529D01*
G02X1798093Y244500I-143J140D01*
G01X1785643D01*
X1785569Y244470D01*
X1785541Y244441D01*
X1785159Y244059D01*
G02X1785017Y244000I-142J141D01*
G01X1734753D01*
G03X1734611Y243941I0J-200D01*
G01X1733559Y242889D01*
G02X1733417Y242830I-142J141D01*
G01X1724753D01*
G02X1724611Y242889I0J200D01*
G01X1721959Y245541D01*
G02X1721900Y245683I141J142D01*
G01Y250817D01*
G02X1721959Y250959I200J0D01*
G01X1726041Y255041D01*
G03X1726100Y255183I-141J142D01*
G01Y282417D01*
G02X1726159Y282559I200J0D01*
G01X1729541Y285941D01*
G02X1729683Y286000I142J-141D01*
G01X1740557D01*
X1740631Y286030D01*
X1740659Y286059D01*
X1743041Y288441D01*
G03X1743100Y288583I-141J142D01*
G01Y328917D01*
G02X1743159Y329059I200J0D01*
G01X1744643Y330543D01*
G02X1744785Y330602I142J-141D01*
G01X1752659D01*
X1752733Y330632D01*
X1752761Y330661D01*
X1753041Y330941D01*
G03X1753100Y331083I-141J142D01*
G01Y375317D01*
G03X1753041Y375459I-200J0D01*
G01X1744159Y384341D01*
G02X1744100Y384483I141J142D01*
G01Y418517D01*
G02X1744159Y418659I200J0D01*
G01X1746941Y421441D01*
G37*
G36*
G01X1835803Y427600D02*
G02X1835661Y428238I1362J638D01*
G02X1838667I1503J0D01*
G02X1838525Y427600I-1504J0D01*
G01X1838506Y427559D01*
Y425854D01*
X1838519Y425804D01*
X1838533Y425781D01*
G02X1838651Y425337I-776J-444D01*
G01Y424470D01*
G02X1838591Y424328I-200J1D01*
G01X1838474Y424211D01*
G03X1838472Y424209I140J-142D01*
G03X1838415Y424069I143J-140D01*
G01Y422384D01*
G03X1838586Y422206I199J20D01*
G01X1838651D01*
Y421139D01*
G02X1838533Y420695I-894J0D01*
G01X1838519Y420672D01*
X1838506Y420622D01*
Y419917D01*
X1838525Y419876D01*
G02X1838667Y419238I-1362J-638D01*
G02X1835661I-1503J0D01*
G02X1835803Y419876I1504J0D01*
G01X1835822Y419917D01*
Y420622D01*
X1835809Y420672D01*
X1835795Y420695D01*
G02X1835677Y421139I776J444D01*
G01Y422006D01*
G02X1835737Y422148I200J-1D01*
G01X1835854Y422265D01*
G03X1835856Y422267I-140J142D01*
G03X1835913Y422407I-143J140D01*
G01Y424092D01*
G03X1835742Y424270I-199J-20D01*
G01X1835677D01*
Y425337D01*
G02X1835795Y425781I894J0D01*
G01X1835809Y425804D01*
X1835822Y425854D01*
Y427559D01*
X1835803Y427600D01*
G37*
G36*
G01X1845803Y429933D02*
G02X1845662Y430568I1361J635D01*
G02X1848666I1502J0D01*
G02X1848525Y429933I-1502J0D01*
G01X1848506Y429892D01*
Y425854D01*
X1848519Y425804D01*
X1848533Y425781D01*
G02X1848651Y425337I-776J-444D01*
G01Y424470D01*
G02X1848591Y424328I-200J1D01*
G01X1848474Y424211D01*
G03X1848472Y424209I140J-142D01*
G03X1848415Y424069I143J-140D01*
G01Y422384D01*
G03X1848586Y422206I199J20D01*
G01X1848651D01*
Y421139D01*
G02X1848533Y420695I-894J0D01*
G01X1848519Y420672D01*
X1848506Y420622D01*
Y419917D01*
X1848525Y419876D01*
G02X1848667Y419238I-1362J-638D01*
G02X1845661I-1503J0D01*
G02X1845803Y419876I1504J0D01*
G01X1845822Y419917D01*
Y420622D01*
X1845809Y420672D01*
X1845795Y420695D01*
G02X1845677Y421139I776J444D01*
G01Y422006D01*
G02X1845737Y422148I200J-1D01*
G01X1845854Y422265D01*
G03X1845856Y422267I-140J142D01*
G03X1845913Y422407I-143J140D01*
G01Y424092D01*
G03X1845742Y424270I-199J-20D01*
G01X1845677D01*
Y425337D01*
G02X1845795Y425781I894J0D01*
G01X1845809Y425804D01*
X1845822Y425854D01*
Y429892D01*
X1845803Y429933D01*
G37*
G36*
G01X1840803Y431703D02*
G02X1840662Y432338I1361J635D01*
G02X1843666I1502J0D01*
G02X1843525Y431703I-1502J0D01*
G01X1843506Y431662D01*
Y425854D01*
X1843519Y425804D01*
X1843533Y425781D01*
G02X1843651Y425337I-776J-444D01*
G01Y424470D01*
G02X1843591Y424328I-200J1D01*
G01X1843474Y424211D01*
G03X1843472Y424209I140J-142D01*
G03X1843415Y424069I143J-140D01*
G01Y422384D01*
G03X1843586Y422206I199J20D01*
G01X1843651D01*
Y421139D01*
G02X1843533Y420695I-894J0D01*
G01X1843519Y420672D01*
X1843506Y420622D01*
Y419917D01*
X1843525Y419876D01*
G02X1843667Y419238I-1362J-638D01*
G02X1840661I-1503J0D01*
G02X1840803Y419876I1504J0D01*
G01X1840822Y419917D01*
Y420622D01*
X1840809Y420672D01*
X1840795Y420695D01*
G02X1840677Y421139I776J444D01*
G01Y422006D01*
G02X1840737Y422148I200J-1D01*
G01X1840854Y422265D01*
G03X1840856Y422267I-140J142D01*
G03X1840913Y422407I-143J140D01*
G01Y424092D01*
G03X1840742Y424270I-199J-20D01*
G01X1840677D01*
Y425337D01*
G02X1840795Y425781I894J0D01*
G01X1840809Y425804D01*
X1840822Y425854D01*
Y431662D01*
X1840803Y431703D01*
G37*
G36*
G01X1850803Y434903D02*
G02X1850662Y435538I1361J635D01*
G02X1853666I1502J0D01*
G02X1853525Y434903I-1502J0D01*
G01X1853506Y434862D01*
Y425854D01*
X1853519Y425804D01*
X1853533Y425781D01*
G02X1853651Y425337I-776J-444D01*
G01Y424470D01*
G02X1853591Y424328I-200J1D01*
G01X1853474Y424211D01*
G03X1853472Y424209I140J-142D01*
G03X1853415Y424069I143J-140D01*
G01Y422384D01*
G03X1853586Y422206I199J20D01*
G01X1853651D01*
Y421139D01*
G02X1853533Y420695I-894J0D01*
G01X1853519Y420672D01*
X1853506Y420622D01*
Y419917D01*
X1853525Y419876D01*
G02X1853667Y419238I-1362J-638D01*
G02X1850661I-1503J0D01*
G02X1850803Y419876I1504J0D01*
G01X1850822Y419917D01*
Y420622D01*
X1850809Y420672D01*
X1850795Y420695D01*
G02X1850677Y421139I776J444D01*
G01Y422006D01*
G02X1850737Y422148I200J-1D01*
G01X1850854Y422265D01*
G03X1850856Y422267I-140J142D01*
G03X1850913Y422407I-143J140D01*
G01Y424092D01*
G03X1850742Y424270I-199J-20D01*
G01X1850677D01*
Y425337D01*
G02X1850795Y425781I894J0D01*
G01X1850809Y425804D01*
X1850822Y425854D01*
Y434862D01*
X1850803Y434903D01*
G37*
G54D103*
X1124600Y271425D03*
X1141600Y305161D03*
X317000Y58000D03*
X1800100Y187500D03*
X1817500Y188000D03*
X1017300Y322500D03*
X1023492Y346593D03*
X1021414Y355979D03*
X885265Y381000D03*
X1017300Y385600D03*
X1153453Y391353D03*
X894500Y396500D03*
G54D108*
X1809600Y195000D03*
G54D107*
X1811500Y186000D03*
X978600Y310955D03*
X887500Y355680D03*
X885100Y361500D03*
G54D113*
X825900Y372200D03*
X906900D03*
G54D104*
X1470197Y23012D03*
G54D105*
X1480197D03*
G54D100*
X166785Y200472D03*
X243785D03*
X166785Y280472D03*
X243785D03*
X166785Y360472D03*
X243785D03*
X166785Y440472D03*
X243785D03*
X166785Y520472D03*
X243785D03*
X1488500Y200472D03*
X1565500D03*
X1488500Y280472D03*
X1565500D03*
X1488500Y360472D03*
X1565500D03*
X1488500Y440472D03*
X1565500D03*
X1488500Y520472D03*
X1565500D03*
G54D99*
X408100Y180100D03*
Y224500D03*
X1355100Y160000D03*
X1355000Y204400D03*
G54D114*
X623500Y379000D03*
G54D111*
X822087Y313484D03*
X940197D03*
G54D112*
X1856772Y360433D03*
G54D102*
X263780Y659961D03*
X1468504Y628465D03*
X1444882Y659961D03*
G54D115*
X1716930Y503124D03*
X99149Y604098D03*
G54D101*
X287402Y628465D03*
G54D106*
X1529100Y78500D03*
X231600Y81000D03*
G54D109*
X59055Y236614D03*
Y411594D03*
G54D110*
X1673228Y236614D03*
Y411614D03*
%LPD*%
G75*
G36*
G01X1733600Y281000D02*
X1789385D01*
X1790600Y279785D01*
Y246000D01*
X1790100Y245500D01*
X1785600D01*
X1784600Y246500D01*
X1733460D01*
X1731100Y248860D01*
Y278500D01*
X1733600Y281000D01*
G37*
G36*
G01X1761160Y337500D02*
X1761242Y337582D01*
X1762162D01*
X1766210D01*
X1766528Y337900D01*
X1772430D01*
X1772630D01*
X1773360D01*
X1773740Y337520D01*
Y335670D01*
X1773715Y335645D01*
X1775150Y334210D01*
X1777910D01*
X1778510D01*
X1778740Y333980D01*
Y325360D01*
X1778510Y325130D01*
X1778210D01*
X1769740D01*
X1769115Y325755D01*
X1764310Y330560D01*
X1761250D01*
X1761160Y330650D01*
Y331210D01*
X1761254Y331304D01*
X1765000D01*
X1769584Y326720D01*
X1769800D01*
X1773070D01*
X1773400Y327050D01*
Y333650D01*
X1772380Y334670D01*
X1771859D01*
X1769632Y336897D01*
X1768963D01*
X1768513D01*
X1762189D01*
X1761213D01*
X1761160Y336950D01*
Y337500D01*
G37*
G36*
G01X1766379Y322227D02*
X1760670Y327936D01*
Y329326D01*
Y329560D01*
X1760720Y329610D01*
X1764280D01*
X1764345Y329545D01*
Y328355D01*
X1768800Y323900D01*
Y321690D01*
X1768580Y321470D01*
X1766680D01*
X1766379Y321771D01*
Y321787D01*
Y322227D01*
G37*
G36*
G01X1745200Y329600D02*
X1753200D01*
X1753400Y329400D01*
Y327800D01*
X1753100Y327500D01*
X1745200D01*
X1745000Y327700D01*
Y329400D01*
X1745200Y329600D01*
G37*
G36*
G01X1776800Y323700D02*
X1776900Y323800D01*
X1779600D01*
X1780000Y323400D01*
Y305600D01*
Y304400D01*
X1778600Y303000D01*
X1749100D01*
X1747859Y304241D01*
Y305965D01*
Y319785D01*
X1755449Y327375D01*
Y334157D01*
X1755719Y334427D01*
X1756259D01*
X1756639Y334047D01*
Y321400D01*
X1759602Y318437D01*
X1767960D01*
X1768090Y318567D01*
Y318568D01*
X1774868D01*
X1776800Y320500D01*
Y323700D01*
G37*
G36*
G01X1747100Y418000D02*
X1767100D01*
X1768100Y417000D01*
Y353338D01*
X1759009Y344247D01*
Y326487D01*
X1760319Y325177D01*
Y321997D01*
X1760189Y321867D01*
X1757999D01*
X1757789Y322077D01*
Y335377D01*
X1756309Y336857D01*
Y375191D01*
X1746600Y384900D01*
Y417500D01*
X1747100Y418000D01*
G37*
G36*
G01X1775800Y323700D02*
Y321500D01*
X1775400Y321100D01*
X1770200D01*
X1769800Y321500D01*
Y323800D01*
X1770000Y324000D01*
X1775500D01*
X1775800Y323700D01*
G37*
G36*
G01X1778100Y407520D02*
X1784795D01*
X1786080D01*
X1786600Y407000D01*
Y386500D01*
X1785650Y385550D01*
X1778050D01*
X1775531D01*
X1774603Y386478D01*
Y406738D01*
X1775385Y407520D01*
X1778100D01*
G37*
G54D10*
X19685Y-774040D03*
Y766166D03*
X231600Y81000D03*
X566575Y463701D03*
D03*
D03*
X1212478Y300181D03*
X1529100Y78500D03*
X1854331Y-774040D03*
Y766166D03*
G54D20*
X137303Y601693D03*
Y609567D03*
Y617441D03*
Y625315D03*
Y633189D03*
Y641063D03*
Y648937D03*
Y656811D03*
X163878Y601693D03*
X156004D03*
X145177D03*
X163878Y609567D03*
Y617441D03*
Y625315D03*
Y633189D03*
X156004Y609567D03*
Y617441D03*
Y625315D03*
Y633189D03*
X145177Y609567D03*
Y617441D03*
Y625315D03*
Y633189D03*
X163878Y641063D03*
Y648937D03*
Y656811D03*
X156004Y641063D03*
Y648937D03*
Y656811D03*
X145177Y641063D03*
Y648937D03*
Y656811D03*
X163878Y664685D03*
X156004D03*
X145177D03*
X192126Y633189D03*
Y625315D03*
Y617441D03*
Y656811D03*
Y648937D03*
Y664685D03*
X200000Y633189D03*
Y625315D03*
Y617441D03*
X215748Y633189D03*
Y625315D03*
Y617441D03*
X223622Y633189D03*
Y625315D03*
X215748Y656811D03*
Y648937D03*
X223622Y656811D03*
Y648937D03*
X200000Y656811D03*
Y648937D03*
X215748Y664685D03*
X223622D03*
X200000D03*
X250866Y20827D03*
Y10197D03*
X255906Y617441D03*
X248032D03*
X255906Y625315D03*
Y633189D03*
X248032D03*
Y625315D03*
X255906Y648937D03*
X248032D03*
X255906Y656811D03*
X248032D03*
X255906Y664685D03*
X248032D03*
X279646Y23012D03*
Y13012D03*
X284646Y18012D03*
X274646D03*
X284646Y8012D03*
X260866Y20827D03*
Y10197D03*
X279528Y617441D03*
X271654D03*
X279528Y625315D03*
Y633189D03*
X271654D03*
Y625315D03*
X279528Y648937D03*
X271654D03*
X279528Y656811D03*
X271654D03*
X279528Y664685D03*
X271654D03*
X289646Y23012D03*
Y13012D03*
X295276Y617441D03*
Y625315D03*
Y633189D03*
X303150D03*
Y625315D03*
Y648937D03*
X295276D03*
X303150Y656811D03*
X295276D03*
X303150Y664685D03*
X295276D03*
X1437008Y617441D03*
X1429134D03*
X1437008Y625315D03*
Y633189D03*
X1429134D03*
Y625315D03*
X1437008Y648937D03*
X1429134D03*
X1437008Y656811D03*
X1429134D03*
X1437008Y664685D03*
X1429134D03*
X1465197Y18012D03*
X1451417Y20827D03*
X1441417D03*
X1451417Y10197D03*
X1441417D03*
X1460630Y617441D03*
X1452756D03*
X1460630Y625315D03*
Y633189D03*
X1452756D03*
Y625315D03*
X1460630Y648937D03*
X1452756D03*
X1460630Y656811D03*
X1452756D03*
X1460630Y664685D03*
X1452756D03*
X1480197Y23012D03*
X1470197D03*
X1480197Y13012D03*
X1470197D03*
X1475197Y18012D03*
Y8012D03*
X1476378Y617441D03*
Y625315D03*
Y633189D03*
X1484252D03*
Y625315D03*
Y648937D03*
X1476378D03*
X1484252Y656811D03*
X1476378D03*
X1484252Y664685D03*
X1476378D03*
X1508661Y633189D03*
Y625315D03*
Y617441D03*
X1516535Y633189D03*
Y625315D03*
Y617441D03*
X1508661Y656811D03*
Y648937D03*
X1516535Y656811D03*
Y648937D03*
X1508661Y664685D03*
X1516535D03*
X1532283Y633189D03*
Y625315D03*
Y617441D03*
X1540157Y633189D03*
Y625315D03*
X1532283Y656811D03*
Y648937D03*
X1540157Y656811D03*
Y648937D03*
X1532283Y664685D03*
X1540157D03*
X1587107Y601693D03*
X1576280D03*
X1568406D03*
X1587107Y609567D03*
Y617441D03*
Y625315D03*
Y633189D03*
X1576280Y609567D03*
Y617441D03*
Y625315D03*
Y633189D03*
X1568406Y609567D03*
Y617441D03*
Y625315D03*
Y633189D03*
X1587107Y641063D03*
Y648937D03*
Y656811D03*
X1576280Y641063D03*
Y648937D03*
Y656811D03*
X1568406Y641063D03*
Y648937D03*
Y656811D03*
X1587107Y664685D03*
X1576280D03*
X1594981Y601693D03*
Y609567D03*
Y617441D03*
Y625315D03*
Y633189D03*
Y641063D03*
Y648937D03*
Y656811D03*
Y664685D03*
G54D11*
X3018Y23930D03*
X10493Y5830D03*
X3018Y43930D03*
Y83930D03*
Y63930D03*
Y103930D03*
Y143930D03*
Y123930D03*
Y163930D03*
Y203930D03*
Y183930D03*
Y223930D03*
Y263930D03*
Y243930D03*
Y283930D03*
Y323930D03*
Y303930D03*
Y343930D03*
Y383930D03*
Y363930D03*
Y403930D03*
Y443930D03*
Y423930D03*
Y463930D03*
Y503930D03*
Y483930D03*
Y523930D03*
Y563930D03*
Y543930D03*
Y583930D03*
X15642Y619715D03*
X3018Y603930D03*
X30709Y3014D03*
X35455Y620194D03*
X75455D03*
X55455D03*
X81406Y3042D03*
X101406D03*
X95455Y620194D03*
X121406Y3042D03*
X137355Y120500D03*
X134600Y150000D03*
Y134000D03*
X114923Y623982D03*
X124901Y640105D03*
X161406Y3042D03*
X141406D03*
X156785Y101285D03*
X154778Y672779D03*
X181406Y3042D03*
X187600Y106500D03*
X176785Y102000D03*
X194778Y672779D03*
X174778D03*
X201406Y3042D03*
X221406D03*
X205061Y85500D03*
Y79000D03*
Y75000D03*
Y71500D03*
Y67500D03*
X211425Y106075D03*
X205061Y89500D03*
Y93000D03*
Y97000D03*
X200600Y109059D03*
X225829Y103412D03*
Y99503D03*
X225953Y95780D03*
X225891Y92305D03*
X210925Y115575D03*
X205100Y123000D03*
X214778Y672779D03*
X229829Y103412D03*
X233329D03*
X237329D03*
X229829Y99503D03*
X233329D03*
X237329D03*
X229953Y95780D03*
X233453D03*
X237453D03*
X229891Y92305D03*
X233391D03*
X237391D03*
X254778Y672779D03*
X234778D03*
X274778D03*
X317000Y58000D03*
X314766Y39211D03*
X317766D03*
X317000Y74475D03*
Y64500D03*
X311956Y651522D03*
X294778Y672779D03*
X325500Y15000D03*
Y18000D03*
Y21000D03*
X340500D03*
Y18000D03*
Y15000D03*
X337500Y21000D03*
Y18000D03*
Y15000D03*
X334500Y21000D03*
Y18000D03*
Y15000D03*
X331500Y21000D03*
Y18000D03*
Y15000D03*
X328500Y21000D03*
Y18000D03*
Y15000D03*
X323766Y39211D03*
X320766D03*
X321500Y74475D03*
Y66500D03*
X332500Y63300D03*
X330500Y74476D03*
X324000Y77000D03*
X321000Y63000D03*
X326000Y74476D03*
X345412Y435017D03*
Y455017D03*
Y475017D03*
Y495017D03*
Y515017D03*
Y535017D03*
Y555017D03*
Y575017D03*
Y595017D03*
X342119Y613510D03*
X331285Y620008D03*
X369192Y38417D03*
X372192D03*
X378192D03*
X375192D03*
X362127Y406608D03*
X350024Y418335D03*
X396216Y46875D03*
X408100Y180100D03*
Y224500D03*
X399680Y402510D03*
X379680D03*
X428277Y167056D03*
X438100Y170000D03*
X430608Y211389D03*
X438100Y214500D03*
X419680Y402510D03*
X454738Y56000D03*
X451738D03*
X448738D03*
X445738D03*
X442738D03*
X454738Y68000D03*
Y65000D03*
Y62000D03*
Y59000D03*
X451738D03*
Y62000D03*
Y65000D03*
Y68000D03*
X448738Y59000D03*
Y62000D03*
Y65000D03*
Y68000D03*
X445738Y59000D03*
Y62000D03*
Y65000D03*
Y68000D03*
X442738Y59000D03*
Y62000D03*
Y65000D03*
Y68000D03*
X441938Y87700D03*
X454738Y112400D03*
Y109400D03*
Y106400D03*
Y103400D03*
X451738D03*
Y106400D03*
Y109400D03*
Y112400D03*
X448738Y103400D03*
Y106400D03*
Y109400D03*
Y112400D03*
X445738Y103400D03*
Y106400D03*
Y109400D03*
Y112400D03*
X442738Y103400D03*
Y106400D03*
Y109400D03*
Y112400D03*
X454738Y100400D03*
X451738D03*
X448738D03*
X445738D03*
X442738D03*
X454738Y147800D03*
X451738D03*
X448738D03*
X445738D03*
X442738D03*
X454738Y144800D03*
X451738D03*
X448738D03*
X445738D03*
X442738D03*
X441938Y132100D03*
X454738Y156800D03*
Y153800D03*
Y150800D03*
X451738D03*
Y153800D03*
Y156800D03*
X448738Y150800D03*
Y153800D03*
Y156800D03*
X445738Y150800D03*
Y153800D03*
Y156800D03*
X442738Y150800D03*
Y153800D03*
Y156800D03*
X441938Y176500D03*
X454738Y201200D03*
Y198200D03*
Y195200D03*
Y192200D03*
X451738D03*
Y195200D03*
Y198200D03*
Y201200D03*
X448738Y192200D03*
Y195200D03*
Y198200D03*
Y201200D03*
X445738Y192200D03*
Y195200D03*
Y198200D03*
Y201200D03*
X442738Y192200D03*
Y195200D03*
Y198200D03*
Y201200D03*
X454738Y189200D03*
X451738D03*
X448738D03*
X445738D03*
X442738D03*
X454738Y239600D03*
Y236600D03*
X451738D03*
Y239600D03*
X448738Y236600D03*
Y239600D03*
X445738Y236600D03*
Y239600D03*
X442738Y236600D03*
Y239600D03*
X454738Y233600D03*
X451738D03*
X448738D03*
X445738D03*
X442738D03*
X441938Y220900D03*
X454738Y245600D03*
Y242600D03*
X451738D03*
Y245600D03*
X448738Y242600D03*
Y245600D03*
X445738Y242600D03*
Y245600D03*
X442738Y242600D03*
Y245600D03*
X441938Y265300D03*
X448738Y278000D03*
X451738D03*
X454738D03*
X448738Y290000D03*
Y287000D03*
Y284000D03*
Y281000D03*
X451738Y290000D03*
Y287000D03*
Y284000D03*
Y281000D03*
X454738D03*
Y284000D03*
Y287000D03*
Y290000D03*
X445738D03*
Y287000D03*
Y284000D03*
Y281000D03*
Y278000D03*
X442738Y290000D03*
Y287000D03*
Y284000D03*
Y281000D03*
Y278000D03*
X441938Y309700D03*
X468946Y338216D03*
X465946D03*
X468946Y341216D03*
X465946D03*
X458946Y338216D03*
X455946D03*
X458946Y341216D03*
X455946D03*
Y357216D03*
X458946D03*
X468946Y357016D03*
X465946D03*
X459680Y402510D03*
X439680D03*
X498923Y37456D03*
X495923D03*
X492923D03*
X489923D03*
X471946Y338216D03*
Y341216D03*
X481446Y338216D03*
X478446D03*
X481446Y341216D03*
X478446D03*
X484446Y338216D03*
Y341216D03*
X471946Y357016D03*
X479680Y402510D03*
X501923Y37456D03*
X504923D03*
X510923D03*
X507923D03*
X528084Y77900D03*
Y74900D03*
Y71900D03*
Y68900D03*
Y65900D03*
X525084Y77900D03*
Y74900D03*
Y71900D03*
Y68900D03*
Y65900D03*
X522084Y77900D03*
Y74900D03*
Y71900D03*
Y68900D03*
Y65900D03*
X525084Y116300D03*
Y113300D03*
Y110300D03*
X522084Y113300D03*
Y116300D03*
Y110300D03*
X528084Y116300D03*
Y113300D03*
Y110300D03*
X525084Y122300D03*
X522084D03*
X525084Y119300D03*
X522084D03*
X528084Y122300D03*
Y119300D03*
X525084Y166700D03*
X522084D03*
X525084Y160700D03*
Y163700D03*
Y157700D03*
Y154700D03*
X522084Y157700D03*
Y163700D03*
Y160700D03*
Y154700D03*
Y199100D03*
Y205100D03*
Y208100D03*
Y202100D03*
X525084Y199100D03*
Y202100D03*
Y208100D03*
Y205100D03*
X522084Y211100D03*
X525084D03*
X522084Y243500D03*
Y249500D03*
Y252500D03*
Y246500D03*
X525084Y243500D03*
Y246500D03*
Y252500D03*
Y249500D03*
X522084Y255500D03*
X525084D03*
X528084Y243500D03*
Y246500D03*
Y252500D03*
Y249500D03*
Y255500D03*
Y299900D03*
X525084D03*
X522084D03*
X528084Y296900D03*
X525084D03*
X522084D03*
X528084Y293900D03*
X525084D03*
X522084D03*
X528084Y290900D03*
Y287900D03*
X525084D03*
Y290900D03*
X522084D03*
Y287900D03*
X517409Y322000D03*
X506309Y329000D03*
Y322000D03*
X517410Y329000D03*
X499680Y402510D03*
X519680D03*
X531084Y77900D03*
Y74900D03*
Y71900D03*
Y68900D03*
Y65900D03*
X551430Y132400D03*
X561155Y160784D03*
X551430Y265600D03*
X531084Y299900D03*
Y296900D03*
Y293900D03*
Y290900D03*
Y287900D03*
X539680Y402510D03*
X559680D03*
X586184Y117800D03*
X583184D03*
X580184D03*
X586184Y114800D03*
X583184D03*
X580184D03*
X586184Y111800D03*
X583184D03*
X580184D03*
X586184Y108800D03*
X583184D03*
X580184D03*
X586184Y105800D03*
X583184D03*
X580184D03*
X563007Y118477D03*
Y114123D03*
X580184Y126800D03*
X583184D03*
X586184D03*
Y123800D03*
X583184D03*
X580184D03*
X586184Y120800D03*
X583184D03*
X580184D03*
X562830Y133300D03*
Y136800D03*
Y140300D03*
Y143800D03*
X574230Y132400D03*
X583184Y239000D03*
X580184D03*
X563007Y251677D03*
X576467Y265600D03*
X563007Y247323D03*
X583184Y242000D03*
X580184D03*
X583184Y254000D03*
Y251000D03*
Y248000D03*
Y245000D03*
X580184D03*
Y248000D03*
Y251000D03*
Y254000D03*
X583184Y260000D03*
Y257000D03*
X580184D03*
Y260000D03*
X562830Y270000D03*
Y266500D03*
Y277000D03*
Y273500D03*
X571542Y289065D03*
X565091Y302592D03*
X570443Y302702D03*
X579680Y402510D03*
X595276Y239710D03*
X592476D03*
X620600Y239161D03*
X620466Y246839D03*
X605800Y256500D03*
X609637Y254523D03*
X605700Y259500D03*
X616184Y267000D03*
X604684D03*
X616684Y294500D03*
X602928Y293969D03*
X600875Y295937D03*
X616184Y276000D03*
X604684D03*
Y285000D03*
X616184D03*
X590684Y313800D03*
Y310800D03*
X601675Y305575D03*
X618500Y333500D03*
X619680Y402510D03*
X599680D03*
X645784Y43500D03*
X648784D03*
X645784Y40500D03*
X648784D03*
X645784Y99000D03*
X648784D03*
X645784Y96000D03*
X648784D03*
X622288Y235790D03*
X624788D03*
X640684Y264500D03*
Y269000D03*
X641000Y261500D03*
X644502Y246839D03*
X649200Y254500D03*
X650100Y251500D03*
X623684Y281000D03*
X629018Y277500D03*
X649059Y314000D03*
X632186Y338917D03*
X623500Y379000D03*
X639680Y402510D03*
X651784Y43500D03*
Y40500D03*
X657784D03*
X654784D03*
X657784Y43500D03*
X654784D03*
X651784Y99000D03*
Y96000D03*
X657784D03*
X654784D03*
X657784Y99000D03*
X654784D03*
X676638Y230894D03*
X658600Y237700D03*
X655600D03*
X664484Y212500D03*
X666984D03*
X672484D03*
X674984D03*
X679484D03*
X681684Y230820D03*
X657259Y263000D03*
X660684Y262500D03*
X654100Y263000D03*
X651100Y266000D03*
X679184Y278980D03*
X673684Y280950D03*
X676684D03*
X670184Y288500D03*
X662184Y280500D03*
Y288500D03*
Y284500D03*
X659000Y284000D03*
X676184Y274000D03*
X657500Y330075D03*
X662075Y320000D03*
X675100Y304500D03*
X662125Y308500D03*
X671000Y315760D03*
X668000Y311500D03*
X663500D03*
X657500Y326925D03*
X662100Y304500D03*
X658925Y320000D03*
X659680Y402510D03*
X679680D03*
X693863Y189760D03*
X688900Y184260D03*
X704200Y206569D03*
X702223Y197419D03*
X704240Y185000D03*
X681984Y212500D03*
X685484D03*
X687984D03*
X689684Y230762D03*
X683592Y259908D03*
X688945Y259761D03*
X695259Y248020D03*
X706984Y261100D03*
X710084D03*
X691794Y261073D03*
X692109Y248020D03*
X686784Y268100D03*
X695584D03*
X698433Y247119D03*
X702984Y283500D03*
X706684D03*
X702984Y272400D03*
X706684D03*
X686784Y278000D03*
X695584D03*
X686784Y287900D03*
X695684D03*
X710900Y324100D03*
X696613Y324032D03*
X693904D03*
X691759Y309000D03*
X699680Y402510D03*
X736554Y128056D03*
X739554Y131056D03*
Y128056D03*
X732100Y185000D03*
X729100D03*
X720100D03*
X723100D03*
X726100Y188000D03*
X729100D03*
X732100D03*
X723100D03*
X720100D03*
X726000Y231500D03*
X729000D03*
X723000D03*
X720000D03*
X732000D03*
Y228500D03*
X720000D03*
X723000D03*
X726000D03*
X729000D03*
X712000Y215500D03*
X730600Y270000D03*
X727600D03*
X719484Y278980D03*
X725000Y292500D03*
X722925Y299500D03*
X719433Y328087D03*
X734500Y307425D03*
X719500Y315500D03*
X734500Y310575D03*
X717401Y329996D03*
X739680Y402510D03*
X719680D03*
X742554Y131056D03*
X770700Y206900D03*
X749600Y185000D03*
X752600D03*
X755600D03*
X758600D03*
X746600Y188000D03*
X758600D03*
X755600D03*
X752600D03*
X749600D03*
X746600Y185000D03*
X758500Y231500D03*
X746500D03*
X755500D03*
X752500D03*
X749500D03*
X746500Y228500D03*
X755500D03*
X752500D03*
X749500D03*
X758500D03*
X759680Y402510D03*
X776000Y206600D03*
X779680Y402510D03*
X799680D03*
X819680D03*
X862600Y29500D03*
X839680Y402510D03*
X859680D03*
X867100Y28000D03*
X872533Y29432D03*
X867100Y31500D03*
X887500Y355680D03*
X885100Y361500D03*
X885265Y381000D03*
X878175Y374100D03*
Y364709D03*
X880500Y369500D03*
X879680Y402510D03*
X919680D03*
X899680D03*
X894500Y396500D03*
X954200Y200200D03*
X954600Y207200D03*
X939680Y402510D03*
X983500Y185000D03*
Y188000D03*
X974500Y185000D03*
X977500D03*
X980500Y188000D03*
X977500D03*
X974500D03*
Y231500D03*
X977500D03*
X983500D03*
X980500D03*
X983500Y228500D03*
X980500D03*
X977500D03*
X974500D03*
X978600Y310955D03*
X959680Y402510D03*
X979680D03*
X990954Y131056D03*
Y128056D03*
X993954Y131056D03*
Y128056D03*
X996954Y131056D03*
X986500Y185000D03*
Y188000D03*
X1004000Y185000D03*
X1001000Y188000D03*
X1004000D03*
X1007000Y185000D03*
X1010000D03*
X1013000D03*
Y188000D03*
X1010000D03*
X1007000D03*
X1001000Y185000D03*
X1004000Y231500D03*
X1007000D03*
X1010000D03*
X1001000D03*
X986500D03*
X1013000D03*
X986500Y228500D03*
X1013000D03*
X1004000D03*
X1007000D03*
X1010000D03*
X1001000D03*
X999680Y402510D03*
X1030100Y207500D03*
X1034537Y201437D03*
X1024600Y185000D03*
X1024525Y215000D03*
X1034360Y254000D03*
X1032500Y281800D03*
X1029500D03*
X1042800Y273020D03*
X1017300Y322500D03*
X1026270Y303729D03*
X1023492Y346593D03*
X1021414Y355979D03*
X1017300Y385600D03*
X1039680Y402510D03*
X1019680D03*
X1074500Y43500D03*
Y99000D03*
X1047163Y197437D03*
X1061600Y228000D03*
X1064600D03*
X1073600D03*
X1070600D03*
X1066600Y264100D03*
X1059300Y268500D03*
X1055600D03*
X1070525Y243000D03*
X1066700Y274000D03*
Y283900D03*
X1052200Y290900D03*
X1055300D03*
X1070490Y290927D03*
X1055600Y279600D03*
X1059300D03*
X1073339Y292239D03*
X1062600Y305000D03*
X1070175Y303980D03*
X1067025D03*
X1072600Y324000D03*
X1064600D03*
X1065800Y339500D03*
X1063300D03*
X1073800D03*
X1071300D03*
X1059680Y402510D03*
X1077500Y43500D03*
Y40500D03*
X1074500D03*
X1080500D03*
X1083500D03*
X1086500D03*
X1080500Y43500D03*
X1083500D03*
X1086500D03*
X1077500Y99000D03*
Y96000D03*
X1074500D03*
X1080500D03*
X1083500D03*
X1086500D03*
X1080500Y99000D03*
X1083500D03*
X1086500D03*
X1092100Y263500D03*
X1100100Y243500D03*
X1100500Y263500D03*
X1101500Y268500D03*
X1100100Y247500D03*
X1075500Y264100D03*
X1085600Y271050D03*
X1101500Y271500D03*
X1083100Y273020D03*
X1088079Y274980D03*
X1087100Y282500D03*
X1101600Y289500D03*
X1080600Y294000D03*
X1075500Y274000D03*
Y283900D03*
X1102600Y296000D03*
X1086100Y278000D03*
X1103661Y307700D03*
X1080600Y324000D03*
X1081800Y339500D03*
X1079300D03*
X1086800D03*
X1089300D03*
X1094500Y355600D03*
Y360500D03*
X1079680Y402510D03*
X1099680D03*
X1129800Y265400D03*
X1108100Y289000D03*
X1121600Y287500D03*
Y283000D03*
X1118500D03*
X1105025Y289000D03*
X1111100Y291500D03*
Y285000D03*
X1121100Y296000D03*
X1124600Y271425D03*
X1132113Y274500D03*
X1112000Y296000D03*
X1106661Y307700D03*
X1111100Y300500D03*
X1118000Y303500D03*
X1123100Y319500D03*
X1130100Y305174D03*
X1130510Y307720D03*
X1106000Y364500D03*
X1112500Y364700D03*
X1122000Y366240D03*
X1132000Y367000D03*
X1119680Y402510D03*
X1155366Y38982D03*
X1152366D03*
X1158366D03*
X1161366D03*
X1143500Y251500D03*
X1149600Y255000D03*
X1160990Y252134D03*
X1146100Y267000D03*
X1157600D03*
X1154025Y247000D03*
X1156584Y292488D03*
X1156509Y295396D03*
X1157600Y276000D03*
X1146100D03*
Y285000D03*
X1157600D03*
X1136000Y278953D03*
X1141600Y305161D03*
X1154600Y321050D03*
X1143100Y322500D03*
Y320000D03*
X1157800Y312050D03*
X1157138Y303000D03*
X1141600Y312839D03*
X1141500Y347500D03*
X1138500D03*
X1162425Y340500D03*
X1147000Y342500D03*
X1166000Y352500D03*
X1163000D03*
X1153500Y342500D03*
X1135000Y366500D03*
X1139000D03*
X1159680Y402510D03*
X1139680D03*
X1176100Y105800D03*
Y108800D03*
X1182100Y105800D03*
Y108800D03*
X1179100D03*
Y105800D03*
X1176100Y111800D03*
Y114800D03*
Y117800D03*
X1182100Y111800D03*
Y114800D03*
Y117800D03*
X1179100D03*
Y114800D03*
Y111800D03*
X1176100Y126800D03*
Y123800D03*
Y120800D03*
X1182100Y126800D03*
Y123800D03*
Y120800D03*
X1179100D03*
Y123800D03*
Y126800D03*
X1187700Y132400D03*
X1197425Y160284D03*
X1176100Y239000D03*
X1179100D03*
X1182100D03*
X1187700Y265600D03*
X1176100Y254000D03*
Y251000D03*
Y248000D03*
Y245000D03*
Y257000D03*
Y260000D03*
Y242000D03*
X1171600Y241500D03*
X1179100Y242000D03*
Y260000D03*
Y257000D03*
Y245000D03*
Y248000D03*
Y251000D03*
Y254000D03*
X1182100D03*
Y251000D03*
Y248000D03*
Y245000D03*
Y257000D03*
Y260000D03*
Y242000D03*
X1173500Y298500D03*
X1176200Y316500D03*
X1173200D03*
X1176000Y350000D03*
X1167800Y355000D03*
X1168200Y349700D03*
X1165575Y340500D03*
X1171700Y349900D03*
X1178900Y359620D03*
X1179500Y350000D03*
X1178500Y368740D03*
X1179680Y402510D03*
X1223866Y38482D03*
X1220866D03*
X1199277Y118477D03*
Y114123D03*
X1210500Y132400D03*
X1199100Y140300D03*
Y133300D03*
Y143800D03*
Y136800D03*
X1199277Y247323D03*
X1210500Y265600D03*
X1199277Y251677D03*
X1199100Y270000D03*
Y266500D03*
Y277000D03*
X1201037Y318912D03*
X1197127Y314264D03*
X1225930Y359148D03*
X1199680Y402510D03*
X1219680D03*
X1226866Y38482D03*
X1229866D03*
X1240200Y77900D03*
Y74900D03*
Y71900D03*
Y68900D03*
Y65900D03*
X1237200D03*
Y68900D03*
Y71900D03*
Y74900D03*
Y77900D03*
X1234200Y65900D03*
Y68900D03*
Y71900D03*
Y74900D03*
Y77900D03*
X1231200Y65900D03*
Y68900D03*
Y71900D03*
Y74900D03*
Y77900D03*
X1234200Y116300D03*
Y113300D03*
Y110300D03*
X1237200Y116300D03*
Y113300D03*
Y110300D03*
X1240200D03*
Y113300D03*
Y116300D03*
X1234200Y122300D03*
Y119300D03*
X1237200Y122300D03*
Y119300D03*
X1240200D03*
Y122300D03*
X1237200Y166700D03*
Y163700D03*
Y160700D03*
Y157700D03*
Y154700D03*
X1240200D03*
Y157700D03*
Y160700D03*
Y163700D03*
Y166700D03*
X1237200Y205100D03*
Y202100D03*
Y199100D03*
Y208100D03*
X1240200D03*
Y199100D03*
Y202100D03*
Y205100D03*
X1237200Y211100D03*
X1240200D03*
X1234200Y249500D03*
Y246500D03*
Y243500D03*
Y252500D03*
X1237200Y249500D03*
Y246500D03*
Y243500D03*
Y252500D03*
X1234200Y255500D03*
X1237200D03*
X1240200Y252500D03*
Y243500D03*
Y246500D03*
Y249500D03*
Y255500D03*
Y293900D03*
Y290900D03*
Y287900D03*
Y299900D03*
Y296900D03*
X1237200D03*
Y287900D03*
Y290900D03*
Y293900D03*
Y299900D03*
X1234200Y296900D03*
Y287900D03*
Y290900D03*
Y293900D03*
Y299900D03*
X1231200Y293900D03*
Y290900D03*
Y287900D03*
Y296900D03*
Y299900D03*
X1244874Y330000D03*
X1255975D03*
X1242930Y359148D03*
Y356148D03*
X1245930Y359148D03*
Y356148D03*
X1248930Y359148D03*
Y356148D03*
X1231930D03*
Y359148D03*
X1228930Y356148D03*
Y359148D03*
X1225930Y356148D03*
X1255975Y337000D03*
X1253930Y379648D03*
X1250930D03*
X1247930D03*
X1239680Y402510D03*
X1264366Y38482D03*
X1261366D03*
X1267366D03*
X1270366D03*
X1260340Y359284D03*
Y356284D03*
X1263340Y359284D03*
Y356284D03*
X1266340Y359284D03*
Y356284D03*
X1286113Y378312D03*
X1265340Y379784D03*
X1268340D03*
X1271340D03*
X1259680Y402510D03*
X1279680D03*
X1313366Y38482D03*
X1307366D03*
X1310366D03*
X1307700Y78900D03*
Y81900D03*
X1310700D03*
Y78900D03*
X1313700Y81900D03*
Y78900D03*
X1307700Y84900D03*
Y87900D03*
X1310700D03*
Y84900D03*
X1313700Y87900D03*
Y84900D03*
X1307700Y90900D03*
X1310700D03*
X1313700D03*
X1307700Y123300D03*
Y126300D03*
X1310700D03*
Y123300D03*
X1313700Y126300D03*
Y123300D03*
X1307700Y129300D03*
Y132300D03*
Y135300D03*
X1310700D03*
Y132300D03*
Y129300D03*
X1313700Y135300D03*
Y132300D03*
Y129300D03*
Y167700D03*
Y170700D03*
Y173700D03*
Y176700D03*
X1310700Y167700D03*
Y170700D03*
Y173700D03*
Y176700D03*
X1307700D03*
Y173700D03*
Y170700D03*
Y167700D03*
X1313700Y179700D03*
X1310700D03*
X1307700D03*
Y212100D03*
Y215100D03*
X1310700D03*
Y212100D03*
X1313700Y215100D03*
Y212100D03*
X1307700Y218100D03*
Y221100D03*
Y224100D03*
X1310700D03*
Y221100D03*
Y218100D03*
X1313700Y224100D03*
Y221100D03*
Y218100D03*
X1307700Y256500D03*
Y259500D03*
X1310700D03*
Y256500D03*
X1313700Y259500D03*
Y256500D03*
X1307700Y262500D03*
Y265500D03*
Y268500D03*
X1310700D03*
Y265500D03*
Y262500D03*
X1313700Y268500D03*
Y265500D03*
Y262500D03*
X1307700Y300900D03*
Y303900D03*
X1310700D03*
Y300900D03*
X1313700Y303900D03*
Y300900D03*
X1307700Y306900D03*
Y309900D03*
Y312900D03*
X1310700D03*
Y309900D03*
Y306900D03*
X1313700Y309900D03*
Y306900D03*
X1286113Y375312D03*
X1289113Y378312D03*
Y375312D03*
X1292113Y378312D03*
Y375312D03*
Y372312D03*
X1289113D03*
X1299680Y402510D03*
X1316366Y38482D03*
X1316700Y81900D03*
Y78900D03*
X1319700Y81900D03*
Y78900D03*
X1316700Y87900D03*
Y84900D03*
X1319700Y87900D03*
Y84900D03*
X1320346Y67900D03*
X1316700Y90900D03*
X1319700D03*
X1320346Y112300D03*
X1316700Y126300D03*
Y123300D03*
X1319700Y126300D03*
Y123300D03*
X1316700Y135300D03*
Y132300D03*
Y129300D03*
X1319700Y135300D03*
Y132300D03*
Y129300D03*
X1334140Y146642D03*
X1319700Y167700D03*
Y170700D03*
Y173700D03*
Y176700D03*
X1316700Y167700D03*
Y170700D03*
Y173700D03*
Y176700D03*
X1324100Y150500D03*
X1320346Y156700D03*
X1324100Y194900D03*
X1332671Y190644D03*
X1320346Y201100D03*
X1316700Y215100D03*
Y212100D03*
X1319700Y215100D03*
Y212100D03*
X1316700Y224100D03*
Y221100D03*
Y218100D03*
X1319700Y224100D03*
Y221100D03*
Y218100D03*
X1316700Y259500D03*
Y256500D03*
X1319700Y259500D03*
Y256500D03*
X1316700Y268500D03*
Y265500D03*
Y262500D03*
X1319700Y268500D03*
Y265500D03*
Y262500D03*
X1320346Y245500D03*
Y289900D03*
X1316700Y303900D03*
Y300900D03*
X1319700Y303900D03*
Y300900D03*
X1316700Y306900D03*
X1339680Y402510D03*
X1319680D03*
X1355310Y38893D03*
X1352310D03*
X1349310D03*
X1358310D03*
X1355100Y160000D03*
X1355000Y204400D03*
X1359620Y402940D03*
X1406230Y18076D03*
Y15076D03*
X1403230Y21076D03*
Y18076D03*
Y15076D03*
X1400230Y21076D03*
Y18076D03*
X1397230Y15076D03*
Y18076D03*
Y21076D03*
X1386882Y434539D03*
Y454539D03*
Y474539D03*
Y494539D03*
Y514539D03*
Y534539D03*
Y554539D03*
Y574539D03*
Y594539D03*
X1389643Y612723D03*
X1403035Y620181D03*
X1412230Y21076D03*
Y18076D03*
Y15076D03*
X1409230Y21076D03*
Y18076D03*
Y15076D03*
X1422310Y40481D03*
X1419310D03*
X1416310D03*
X1425310D03*
X1420335Y635388D03*
Y655388D03*
X1428754Y670547D03*
X1445829Y672778D03*
X1465829D03*
X1494728Y83500D03*
X1490000Y80500D03*
X1499228Y74500D03*
X1490000Y84000D03*
X1494728Y66500D03*
X1490228D03*
X1491918Y107773D03*
Y110773D03*
Y113773D03*
Y104773D03*
X1488918D03*
Y113773D03*
Y110773D03*
Y107773D03*
X1485918Y104773D03*
Y113773D03*
Y110773D03*
Y107773D03*
X1482918Y104773D03*
Y113773D03*
Y110773D03*
Y107773D03*
X1485829Y672778D03*
X1508460Y3003D03*
X1505100Y64500D03*
X1503728Y74477D03*
X1527100Y108500D03*
Y98925D03*
X1524600Y111500D03*
X1505829Y672778D03*
X1525829D03*
X1548460Y3003D03*
X1528460D03*
X1531600Y96941D03*
X1551000Y96500D03*
X1545829Y672778D03*
X1588460Y3003D03*
X1568460D03*
X1567500Y67000D03*
X1565829Y672778D03*
X1585829D03*
X1608460Y3003D03*
X1609100Y85500D03*
Y82000D03*
X1606100Y85500D03*
Y82000D03*
X1609100Y69500D03*
Y66000D03*
Y62500D03*
X1606100Y69500D03*
Y66000D03*
Y62500D03*
X1618800Y76700D03*
X1615800Y82700D03*
Y79700D03*
Y76700D03*
X1602100Y85500D03*
Y82000D03*
Y69500D03*
Y66000D03*
Y62500D03*
X1594930Y115000D03*
X1614100Y110000D03*
Y115000D03*
X1609100Y89000D03*
X1606100D03*
X1602100D03*
X1597100Y145000D03*
Y126000D03*
X1614100Y125000D03*
Y120000D03*
Y130000D03*
X1618100Y148925D03*
X1613527Y627220D03*
X1607226Y650448D03*
X1602599Y667628D03*
X1648460Y3003D03*
X1628460D03*
X1618800Y79700D03*
Y82700D03*
X1647800Y83200D03*
Y77200D03*
Y80200D03*
X1622295Y114940D03*
X1629870Y104240D03*
X1625370Y103940D03*
X1642037Y104134D03*
X1643537Y101434D03*
X1640037D03*
X1638537Y104134D03*
X1645537D03*
X1647037Y101434D03*
X1632336Y109117D03*
X1631323Y115140D03*
X1624500Y142500D03*
Y146000D03*
X1622295Y118940D03*
X1647837Y121812D03*
X1638707Y132954D03*
X1644917Y124581D03*
X1641932Y122969D03*
X1635000Y152925D03*
X1623100Y172500D03*
Y178000D03*
X1650117Y180000D03*
X1622100Y155931D03*
X1626000Y163500D03*
Y167500D03*
X1626925Y156000D03*
X1629000Y175000D03*
X1631585Y188777D03*
X1624000Y189000D03*
X1642000Y184500D03*
X1645000D03*
X1628658Y620261D03*
X1648675Y620226D03*
X1657050Y102380D03*
X1662000Y106000D03*
X1660250Y113860D03*
X1657050Y116760D03*
Y113860D03*
X1660250Y116760D03*
X1669800Y120400D03*
X1675800D03*
X1651037Y99734D03*
X1658500Y138000D03*
X1649197Y132915D03*
X1650990Y122034D03*
X1667000Y138000D03*
X1672800Y120400D03*
X1656657Y127365D03*
X1651325Y125076D03*
X1649500Y173398D03*
X1676350Y160251D03*
X1672050Y181550D03*
X1668075Y189500D03*
X1679176Y194760D03*
X1664000Y202500D03*
X1661500Y199000D03*
X1658000Y179500D03*
X1654000Y192500D03*
X1660000Y193500D03*
X1652600Y212000D03*
X1668675Y620226D03*
X1708460Y3003D03*
X1692000Y76570D03*
X1695500Y76500D03*
X1706100Y92000D03*
X1701350Y114250D03*
X1696600Y119000D03*
X1682500Y121825D03*
X1697976Y148000D03*
X1690100Y127375D03*
X1685100Y127500D03*
X1702525Y129500D03*
X1685976Y148000D03*
X1692600Y135975D03*
X1688100Y145560D03*
X1705100Y140500D03*
X1707100Y142500D03*
X1685000Y133000D03*
X1702600Y171500D03*
X1697976Y164500D03*
Y159000D03*
Y175500D03*
Y170000D03*
Y153500D03*
X1680000Y156500D03*
X1685976Y164500D03*
Y159000D03*
Y153500D03*
Y175500D03*
Y170000D03*
X1701100Y178500D03*
X1688100Y173060D03*
Y162060D03*
X1709600Y158000D03*
X1701000Y159000D03*
Y164500D03*
X1685975Y186500D03*
X1701100Y182000D03*
X1688100Y184220D03*
X1697975Y181000D03*
X1704600Y201500D03*
X1685976Y181000D03*
X1702075Y205500D03*
X1688692Y620191D03*
X1708692D03*
X1729255Y25347D03*
Y45347D03*
X1718675Y88000D03*
X1732786Y58461D03*
X1719075Y107016D03*
Y112000D03*
X1718675Y99000D03*
Y93500D03*
X1713524Y109500D03*
Y114500D03*
X1721685Y95940D03*
X1727200Y104500D03*
X1738000Y124500D03*
X1721000Y142525D03*
X1714100Y144925D03*
X1713525Y134500D03*
Y129500D03*
X1713524Y119500D03*
X1729411Y143661D03*
X1727100Y164280D03*
X1715525Y168500D03*
Y153000D03*
X1722063Y156962D03*
X1726099Y153000D03*
X1720524Y175000D03*
X1717600Y158000D03*
X1720100Y179500D03*
X1729411Y159161D03*
X1733500Y173760D03*
X1712000Y153000D03*
X1728475Y175000D03*
X1731925Y199000D03*
X1714175Y187000D03*
X1738740Y191500D03*
X1729000Y183500D03*
X1724824Y205276D03*
X1711025Y187000D03*
X1721500Y205000D03*
X1721600Y194760D03*
Y198500D03*
X1728600Y387500D03*
X1731100D03*
X1733600D03*
Y397500D03*
X1731100D03*
X1728600D03*
X1729275Y562751D03*
Y542751D03*
Y582751D03*
Y602751D03*
X1753635Y69037D03*
X1767525Y114016D03*
X1759600Y114500D03*
X1767425Y107000D03*
X1764000D03*
X1763500Y113000D03*
X1761600Y124524D03*
X1764000Y142525D03*
X1767425Y137000D03*
X1768500Y142525D03*
X1770575Y137000D03*
X1764100Y119500D03*
X1764000Y158025D03*
X1759925Y178900D03*
X1768500Y158025D03*
X1763925Y170984D03*
Y155484D03*
X1763075Y178900D03*
X1767075Y155484D03*
X1769476Y168500D03*
X1766925Y181500D03*
X1769425Y203000D03*
X1754925D03*
X1754260Y187260D03*
X1768000D03*
X1746000Y191240D03*
X1750563Y198000D03*
X1747925Y204000D03*
X1751600Y238000D03*
Y235500D03*
X1740600D03*
Y238000D03*
X1751600Y233000D03*
X1740600D03*
X1751600Y258000D03*
Y255500D03*
X1740600Y258000D03*
Y255500D03*
Y248000D03*
Y250500D03*
Y253000D03*
X1751600D03*
Y250500D03*
Y248000D03*
X1766432Y250301D03*
Y247301D03*
X1766447Y239798D03*
Y242798D03*
X1751600Y240500D03*
X1740600D03*
X1762454Y320347D03*
X1769300Y329400D03*
X1742109Y345235D03*
Y342435D03*
X1747416Y348293D03*
X1751289Y345227D03*
X1747909Y345335D03*
Y342535D03*
X1744909Y345335D03*
Y342535D03*
X1747416Y351817D03*
X1747235Y355989D03*
Y359564D03*
X1742109Y339635D03*
Y336835D03*
Y334035D03*
X1747909Y339735D03*
Y336935D03*
Y334135D03*
X1744909Y339735D03*
Y336935D03*
Y334135D03*
X1767151Y333311D03*
X1769300Y340600D03*
X1769692Y334649D03*
X1767700Y346200D03*
X1767600Y350000D03*
X1747235Y363689D03*
Y367264D03*
Y371389D03*
Y374964D03*
X1755454Y515746D03*
X1793635Y69037D03*
X1773635D03*
X1772975Y109500D03*
Y104500D03*
X1773076Y117500D03*
X1773000Y142525D03*
X1773500Y121000D03*
Y129500D03*
X1772975Y124500D03*
X1773000Y158000D03*
X1772600Y177300D03*
X1772500Y174000D03*
X1800100Y187500D03*
X1770075Y181500D03*
X1778000Y189500D03*
X1789600Y247000D03*
X1783932Y250357D03*
Y247357D03*
X1775432Y250357D03*
Y247357D03*
X1783947Y239798D03*
Y242798D03*
X1775447Y239798D03*
Y242798D03*
X1789600Y243500D03*
X1777532Y328322D03*
X1795600Y308000D03*
X1777375Y356300D03*
X1777459Y332322D03*
X1777383Y348288D03*
Y352305D03*
X1776100Y361500D03*
Y371500D03*
Y368500D03*
X1776140Y364405D03*
X1784035Y389535D03*
X1781535D03*
X1784035Y386935D03*
X1781535D03*
X1778838Y389508D03*
Y386908D03*
X1781535Y402935D03*
X1784035D03*
X1778838Y402908D03*
X1781535Y405535D03*
X1784035D03*
X1778838Y405508D03*
X1775454Y515746D03*
X1813635Y69037D03*
X1817500Y188000D03*
X1811500Y186000D03*
X1815454Y515746D03*
X1853635Y69037D03*
X1833635D03*
X1842164Y419238D03*
X1847164D03*
X1837164D03*
X1852164D03*
X1844500Y416500D03*
X1842164Y432338D03*
X1847164Y430568D03*
X1852164Y435538D03*
X1837164Y428238D03*
X1847500Y437000D03*
X1835454Y515746D03*
X1855509Y515697D03*
X1871008Y117112D03*
X1871009Y93913D03*
X1871008Y137112D03*
Y177112D03*
Y157112D03*
Y197112D03*
Y237112D03*
Y217112D03*
Y257112D03*
Y297112D03*
Y277112D03*
Y317112D03*
Y357112D03*
Y337112D03*
Y377112D03*
Y417112D03*
Y397112D03*
Y437112D03*
Y477112D03*
Y457112D03*
Y497112D03*
G54D12*
X32284Y541339D03*
X59055Y498032D03*
X1673228D03*
X1700000Y541339D03*
G54D21*
X137303Y664685D03*
X223622Y617441D03*
X274646Y8012D03*
X303150Y617441D03*
X1465197Y8012D03*
X1484252Y617441D03*
X1540157D03*
X1568406Y664685D03*
G54D30*
X208000Y115517D03*
X330500Y69017D03*
X326000D03*
X649500Y257517D03*
X653500Y327017D03*
X676500Y332017D03*
X680500D03*
X1037600Y189017D03*
X1499228Y69018D03*
X1503728D03*
X1524500Y99017D03*
X1628960Y108174D03*
X1627770Y127457D03*
X1645280Y127517D03*
X1638770Y127457D03*
X1631770D03*
X1641000Y201517D03*
X1629600Y192517D03*
X1649270Y127457D03*
X1690100Y132917D03*
X1700100Y121917D03*
X1707200Y160517D03*
X1721000Y145017D03*
Y160517D03*
X1764000Y145017D03*
Y160517D03*
X1746102Y328540D03*
X1852164Y421755D03*
X1837164D03*
X1847164D03*
X1842164D03*
G54D31*
X208000Y103016D03*
X317000Y69016D03*
X321500D03*
X392000Y43816D03*
X663500Y314516D03*
X732000Y307516D03*
X1490228Y69017D03*
X1494728D03*
X1622100Y149016D03*
X1618500Y182516D03*
X1653270Y127456D03*
X1690100Y121916D03*
X1685100D03*
X1707500Y195516D03*
X1711600Y145016D03*
X1717100D03*
X1712000Y160516D03*
X1716500D03*
X1768500Y145016D03*
Y160516D03*
X1773000Y145016D03*
Y160516D03*
X1778000Y192516D03*
X1786600Y243516D03*
X1775816Y336590D03*
X1771816D03*
X1779816D03*
G54D40*
X444838Y87700D03*
Y81900D03*
Y132100D03*
Y126300D03*
Y176500D03*
Y170700D03*
Y220900D03*
Y215100D03*
Y265300D03*
Y259500D03*
Y309700D03*
Y303900D03*
X668000Y320900D03*
Y315100D03*
X1317446Y67900D03*
Y62100D03*
Y112300D03*
Y106500D03*
Y156700D03*
Y150900D03*
Y201100D03*
Y195300D03*
Y239700D03*
Y245500D03*
Y289900D03*
Y284100D03*
G36*
G01X41338Y17716D02*
G03X53150I5906J0D01*
G01Y23763D01*
G02X55572Y32155I15747J1D01*
G03X38916I-8328J5246D01*
G02X41338Y23763I-13327J-8392D01*
G01Y17716D01*
G37*
G36*
G01Y330708D02*
G03X53150I5906J0D01*
G01Y336755D01*
G02X55572Y345147I15747J1D01*
G03X38916I-8328J5246D01*
G02X41338Y336755I-13327J-8392D01*
G01Y330708D01*
G37*
G36*
G01X273622Y53148D02*
G03X285434I5906J0D01*
G01Y59195D01*
G02X287856Y67587I15747J1D01*
G03X271200I-8328J5246D01*
G02X273622Y59195I-13327J-8392D01*
G01Y53148D01*
G37*
G36*
G01X309055Y561023D02*
G03X320867I5906J0D01*
G01Y567070D01*
G02X323289Y575462I15747J1D01*
G03X306633I-8328J5246D01*
G02X309055Y567070I-13327J-8392D01*
G01Y561023D01*
G37*
G36*
G01X387796Y344488D02*
G03X399608I5906J0D01*
G01Y350535D01*
G02X402030Y358927I15747J1D01*
G03X385374I-8328J5246D01*
G02X387796Y350535I-13327J-8392D01*
G01Y344488D01*
G37*
G36*
G01X742126Y64961D02*
G03X753938I5906J0D01*
G01Y71008D01*
G02X756360Y79400I15747J1D01*
G03X739704I-8328J5246D01*
G02X742126Y71008I-13327J-8392D01*
G01Y64961D01*
G37*
G36*
G01Y344488D02*
G03X753938I5906J0D01*
G01Y350535D01*
G02X756360Y358927I15747J1D01*
G03X739704I-8328J5246D01*
G02X742126Y350535I-13327J-8392D01*
G01Y344488D01*
G37*
G36*
G01X978346Y64961D02*
G03X990158I5906J0D01*
G01Y71008D01*
G02X992580Y79400I15747J1D01*
G03X975924I-8328J5246D01*
G02X978346Y71008I-13327J-8392D01*
G01Y64961D01*
G37*
G36*
G01Y344488D02*
G03X990158I5906J0D01*
G01Y350535D01*
G02X992580Y358927I15747J1D01*
G03X975924I-8328J5246D01*
G02X978346Y350535I-13327J-8392D01*
G01Y344488D01*
G37*
G36*
G01X1332678D02*
G03X1344490I5906J0D01*
G01Y350535D01*
G02X1346912Y358927I15747J1D01*
G03X1330256I-8328J5246D01*
G02X1332678Y350535I-13327J-8392D01*
G01Y344488D01*
G37*
G36*
G01X1411418Y561023D02*
G03X1423230I5906J0D01*
G01Y567070D01*
G02X1425652Y575462I15747J1D01*
G03X1408996I-8328J5246D01*
G02X1411418Y567070I-13327J-8392D01*
G01Y561023D01*
G37*
G36*
G01X1446850Y53149D02*
G03X1458662I5906J0D01*
G01Y59196D01*
G02X1461084Y67588I15747J1D01*
G03X1444428I-8328J5246D01*
G02X1446850Y59196I-13327J-8392D01*
G01Y53149D01*
G37*
G36*
G01X1679134Y17716D02*
G03X1690946I5906J0D01*
G01Y23763D01*
G02X1693368Y32155I15747J1D01*
G03X1676712I-8328J5246D01*
G02X1679134Y23763I-13327J-8392D01*
G01Y17716D01*
G37*
G36*
G01Y330708D02*
G03X1690946I5906J0D01*
G01Y336755D01*
G02X1693368Y345147I15747J1D01*
G03X1676712I-8328J5246D01*
G02X1679134Y336755I-13327J-8392D01*
G01Y330708D01*
G37*
G36*
G01X1793306Y96457D02*
G03X1805118I5906J0D01*
G01Y102504D01*
G02X1807540Y110896I15747J1D01*
G03X1790884I-8328J5246D01*
G02X1793306Y102504I-13327J-8392D01*
G01Y96457D01*
G37*
G36*
G01Y478346D02*
G03X1805118I5906J0D01*
G01Y484393D01*
G02X1807540Y492785I15747J1D01*
G03X1790884I-8328J5246D01*
G02X1793306Y484393I-13327J-8392D01*
G01Y478346D01*
G37*
G54D22*
X156785Y110251D03*
X176785D03*
X1555500Y104251D03*
X1575500D03*
G54D32*
X208000Y105983D03*
X317000Y71983D03*
X321500D03*
X392000Y46783D03*
X663500Y317483D03*
X732000Y310483D03*
X1490228Y71984D03*
X1494728D03*
X1622100Y151983D03*
X1618500Y185483D03*
X1653270Y130423D03*
X1690100Y124883D03*
X1685100D03*
X1707500Y198483D03*
X1711600Y147983D03*
X1717100D03*
X1712000Y163483D03*
X1716500D03*
X1768500Y147983D03*
Y163483D03*
X1773000Y147983D03*
Y163483D03*
X1778000Y195483D03*
X1786600Y246483D03*
X1775816Y339557D03*
X1771816D03*
X1779816D03*
G54D14*
X47244Y27558D03*
Y340550D03*
X279528Y62990D03*
X314961Y570865D03*
X393702Y354330D03*
X748032Y74803D03*
Y354330D03*
X984252Y74803D03*
Y354330D03*
X1338584D03*
X1417324Y570865D03*
X1452756Y62991D03*
X1685040Y27558D03*
Y340550D03*
X1799212Y106299D03*
Y488188D03*
G54D50*
X666668Y260500D03*
Y264500D03*
X680584Y302500D03*
X695084Y255500D03*
Y251500D03*
X1085584Y255500D03*
X1098584Y296000D03*
Y300500D03*
X1108084Y291500D03*
Y285000D03*
X1118084Y296000D03*
X1108084Y300500D03*
X1200484Y155300D03*
Y288500D03*
X1524984Y114500D03*
X1615484Y173000D03*
Y169500D03*
Y165500D03*
X1627754Y115140D03*
X1635084Y142000D03*
X1629484Y183000D03*
X1655484Y199000D03*
X1667984Y186500D03*
X1683484Y148000D03*
Y175500D03*
Y153500D03*
Y159000D03*
Y164500D03*
Y170000D03*
Y181000D03*
X1705984Y208000D03*
X1718984Y134500D03*
Y129500D03*
X1720984Y168500D03*
Y153000D03*
X1725984Y179500D03*
X1762984Y174000D03*
X1766984Y153000D03*
Y168500D03*
X1750984Y200500D03*
X1757984D03*
X1770484Y109500D03*
X1770584Y116500D03*
X1770484Y104500D03*
X1770584Y120500D03*
X1770484Y134500D03*
X1772484Y200500D03*
X1774794Y328322D03*
X1770764Y322670D03*
X1777784Y322700D03*
X1774892Y348288D03*
X1774794Y332322D03*
G54D41*
X502988Y71900D03*
Y116300D03*
Y160700D03*
Y205100D03*
Y249500D03*
Y293900D03*
G54D23*
X166785Y150901D03*
X1565500Y144901D03*
G54D60*
X1043360Y197437D03*
X1047100Y189563D03*
X1050840Y197437D03*
X1635340Y149063D03*
X1627860D03*
X1631600Y156937D03*
X1735000Y195937D03*
X1738740Y188063D03*
X1731260D03*
G54D42*
X515009Y329000D03*
X511859D03*
D03*
X508709D03*
X511859Y322000D03*
X508709D03*
X511859D03*
X515009D03*
X1247275Y330000D03*
X1250425D03*
D03*
X1253575D03*
X1250425Y337000D03*
X1253575D03*
X1250425D03*
X1247275D03*
X1635195Y90940D03*
X1638345D03*
X1654615Y102380D03*
X1651465D03*
X1762454Y322905D03*
X1759304D03*
X1771833Y352305D03*
X1774983D03*
G54D51*
X663701Y260500D03*
Y264500D03*
X677617Y302500D03*
X692117Y255500D03*
Y251500D03*
X1082617Y255500D03*
X1095617Y296000D03*
Y300500D03*
X1105117Y291500D03*
Y285000D03*
X1115117Y296000D03*
X1105117Y300500D03*
X1197517Y155300D03*
Y288500D03*
X1522017Y114500D03*
X1612517Y173000D03*
Y169500D03*
Y165500D03*
X1624787Y115140D03*
X1632117Y142000D03*
X1626517Y183000D03*
X1652517Y199000D03*
X1665017Y186500D03*
X1680517Y148000D03*
Y175500D03*
Y153500D03*
Y159000D03*
Y164500D03*
Y170000D03*
Y181000D03*
X1703017Y208000D03*
X1716017Y134500D03*
Y129500D03*
X1718017Y168500D03*
Y153000D03*
X1723017Y179500D03*
X1767517Y109500D03*
X1767617Y116500D03*
X1767517Y104500D03*
X1767617Y120500D03*
X1767517Y134500D03*
X1760017Y174000D03*
X1764017Y153000D03*
Y168500D03*
X1748017Y200500D03*
X1755017D03*
X1769517D03*
X1767797Y322670D03*
X1771827Y328322D03*
X1774817Y322700D03*
X1771925Y348288D03*
X1771827Y332322D03*
G54D33*
X230685Y115614D03*
Y142386D03*
X1501600Y109614D03*
Y136386D03*
G54D24*
X166785Y200472D03*
Y280472D03*
Y360472D03*
Y440472D03*
Y520472D03*
X243785Y200472D03*
Y280472D03*
Y360472D03*
Y440472D03*
Y520472D03*
X1488500Y200472D03*
Y280472D03*
Y360472D03*
Y440472D03*
Y520472D03*
X1565500Y200472D03*
Y280472D03*
Y360472D03*
Y440472D03*
Y520472D03*
G54D15*
X45275Y236614D03*
Y411594D03*
X72835Y236614D03*
X68898Y226771D03*
X59055Y222834D03*
X49212Y226771D03*
X68898Y246457D03*
X49212D03*
X59055Y250394D03*
X68898Y421437D03*
X72835Y411594D03*
X68898Y401751D03*
X59055Y397814D03*
X49212Y401751D03*
Y421437D03*
X59055Y425374D03*
X124600Y120500D03*
X120840Y145500D03*
X121100Y163500D03*
X206900Y110700D03*
X202924Y102925D03*
X254000Y141000D03*
X263000D03*
X325100Y64000D03*
X439400Y81900D03*
X439500Y126300D03*
X436500Y175600D03*
X437200Y219100D03*
X438800Y259500D03*
X439100Y303900D03*
X484100Y325500D03*
X485300Y332100D03*
X536000Y57000D03*
X548000Y68000D03*
X547000Y87000D03*
X543000Y172000D03*
X533000Y156000D03*
X547000Y195000D03*
X546000Y215000D03*
X537000Y227000D03*
X534000Y275000D03*
X564305Y160784D03*
X590298Y282890D03*
X571325Y292757D03*
X590298Y276984D03*
X612684Y297000D03*
X606084Y293100D03*
X616684Y307975D03*
X622184Y308000D03*
X608259Y305000D03*
X639010Y236377D03*
X645900Y242200D03*
X650500Y246600D03*
X637684Y280575D03*
X625684Y273499D03*
X630308Y284500D03*
X649500Y308500D03*
X674800Y269600D03*
X671400Y261000D03*
X666759Y274800D03*
X679184Y273190D03*
X671000Y331925D03*
X685884Y297000D03*
X736554Y131056D03*
X742554Y128056D03*
X726100Y185000D03*
X717384Y273400D03*
X718000Y300000D03*
X714045Y326886D03*
X809400Y362200D03*
X923100D03*
X980500Y185000D03*
X996954Y128056D03*
X1027675Y215000D03*
X1044900Y278600D03*
X1074430Y256461D03*
X1091800Y279100D03*
X1083100Y278810D03*
X1090200Y288600D03*
X1131976Y267500D03*
X1133100Y277700D03*
X1123100Y322500D03*
X1112136Y305400D03*
X1123400Y356300D03*
X1145600Y257500D03*
X1156200Y258900D03*
X1145600Y244025D03*
X1140100Y244000D03*
X1163266Y255311D03*
X1171600Y238000D03*
X1171986Y269110D03*
X1187700Y288000D03*
X1196500Y293284D03*
X1171986Y275016D03*
X1179500Y355000D03*
X1214000Y83000D03*
X1223000Y96000D03*
X1200575Y160284D03*
X1225000Y165000D03*
X1214000Y177000D03*
X1223000Y197000D03*
X1212000Y215000D03*
X1227000Y223000D03*
X1226000Y251000D03*
X1201500Y293284D03*
X1199100Y273500D03*
X1228000Y274000D03*
X1278200Y329500D03*
X1263100Y343200D03*
X1323900Y62100D03*
X1323500Y106500D03*
X1324000Y156000D03*
Y199000D03*
X1323700Y239700D03*
X1323000Y284100D03*
X1406230Y21076D03*
X1400230Y15076D03*
X1498180Y63500D03*
X1529400Y102075D03*
X1524600Y119500D03*
X1607100Y115000D03*
X1618177Y120474D03*
X1611100Y138500D03*
X1612100Y154000D03*
X1620500Y170500D03*
X1620000Y177500D03*
X1630527Y90564D03*
X1646500Y94000D03*
X1627366Y143500D03*
X1622388Y127365D03*
X1634200Y180500D03*
X1636600Y173500D03*
X1621500Y159000D03*
Y165000D03*
X1636500Y168000D03*
Y162500D03*
X1648925Y194000D03*
X1635163Y200500D03*
X1674600Y176000D03*
X1674100Y168280D03*
X1673600Y158500D03*
X1657500Y191500D03*
X1667600Y198500D03*
X1673228Y222834D03*
X1663385Y226771D03*
X1659448Y236614D03*
X1663385Y246457D03*
X1673228Y250394D03*
Y397834D03*
X1663385Y401771D03*
X1659448Y411614D03*
X1663385Y421457D03*
X1673228Y425394D03*
X1690100Y116000D03*
X1708075Y124025D03*
X1710000Y203500D03*
X1687008Y236614D03*
X1683071Y226771D03*
Y246457D03*
Y421457D03*
X1687008Y411614D03*
X1683071Y401771D03*
X1714100Y104500D03*
X1724600Y119500D03*
Y134500D03*
X1726100Y148780D03*
X1726600Y168500D03*
X1724922Y245500D03*
X1761100Y104500D03*
X1760500Y119500D03*
X1761600Y129500D03*
X1758600Y148780D03*
X1759000Y140000D03*
X1758600Y164280D03*
X1759000Y156000D03*
X1755000Y174000D03*
X1744500Y187500D03*
X1763000Y200500D03*
X1749000Y416000D03*
X1778000Y200500D03*
X1809600Y195000D03*
G54D16*
X59055Y236614D03*
Y411594D03*
X1673228Y236614D03*
Y411614D03*
G54D43*
X554149Y116300D03*
Y249500D03*
X571865Y116300D03*
Y249500D03*
X1190419Y116300D03*
Y249500D03*
X1208135Y116300D03*
Y249500D03*
G54D61*
X1259296Y71900D03*
Y116300D03*
Y160700D03*
Y205100D03*
Y249500D03*
Y293900D03*
G54D52*
X674276Y315760D03*
Y319500D03*
Y323240D03*
X683724D03*
Y315760D03*
X1715376Y194760D03*
Y202240D03*
X1724824D03*
Y198500D03*
Y194760D03*
G54D34*
X208000Y118484D03*
X330500Y71984D03*
X326000D03*
X649500Y260484D03*
X653500Y329984D03*
X676500Y334984D03*
X680500D03*
X1037600Y191984D03*
X1499228Y71985D03*
X1503728D03*
X1524500Y101984D03*
X1628960Y111141D03*
X1627770Y130424D03*
X1645280Y130484D03*
X1638770Y130424D03*
X1631770D03*
X1641000Y204484D03*
X1629600Y195484D03*
X1649270Y130424D03*
X1690100Y135884D03*
X1700100Y124884D03*
X1707200Y163484D03*
X1721000Y147984D03*
Y163484D03*
X1764000Y147984D03*
Y163484D03*
X1746102Y331507D03*
X1852164Y424722D03*
X1837164D03*
X1847164D03*
X1842164D03*
G54D70*
X1651774Y118613D03*
G54D25*
X166785Y230000D03*
Y310000D03*
Y390000D03*
Y470000D03*
Y550000D03*
X243785Y230000D03*
Y310000D03*
Y390000D03*
Y470000D03*
Y550000D03*
X1488500Y230000D03*
Y310000D03*
Y390000D03*
Y470000D03*
Y550000D03*
X1565500Y230000D03*
Y310000D03*
Y390000D03*
Y470000D03*
Y550000D03*
G54D62*
X1625426Y79800D03*
X1641174D03*
G54D71*
X1673000Y114646D03*
Y95354D03*
G54D44*
X551430Y135300D03*
X557230D03*
Y142300D03*
X551430D03*
X557230Y149300D03*
X551430D03*
X557230Y268500D03*
X551430D03*
X557230Y282500D03*
X551430D03*
X557230Y275500D03*
X551430D03*
X574230Y135300D03*
X568430D03*
Y142300D03*
X574230D03*
X568430Y149300D03*
X574230D03*
X568430Y268500D03*
X574230D03*
X568430Y282500D03*
X574230D03*
X568430Y275500D03*
X574230D03*
X646900Y251500D03*
X641100D03*
X1114600Y300500D03*
X1120400D03*
X1193500Y135300D03*
X1187700D03*
Y142300D03*
X1193500D03*
Y149300D03*
X1187700D03*
X1193500Y268500D03*
X1187700D03*
X1193500Y282500D03*
X1187700D03*
X1193500Y275500D03*
X1187700D03*
X1204700Y135300D03*
X1210500D03*
Y142300D03*
X1204700D03*
Y149300D03*
X1210500D03*
X1204700Y268500D03*
X1210500D03*
X1204700Y282500D03*
X1210500D03*
X1204700Y275500D03*
X1210500D03*
X1628960Y101030D03*
X1634760D03*
X1628960Y95930D03*
X1634760D03*
G54D53*
X690037Y188000D03*
X682163Y184260D03*
Y191740D03*
X705037Y193500D03*
X697163Y189760D03*
Y197240D03*
X1029063Y201500D03*
X1036937Y205240D03*
Y197760D03*
X1643037Y191000D03*
X1635163Y187260D03*
Y194740D03*
X1758437Y191000D03*
X1750563Y187260D03*
Y194740D03*
X1764563Y187260D03*
Y194740D03*
X1772437Y191000D03*
G54D80*
X1751706Y328965D03*
X1762730Y342351D03*
G54D17*
X99149Y604098D03*
X1024887Y231919D03*
X1641531Y219808D03*
X1716930Y503124D03*
G54D35*
X207874Y639095D03*
X1524409D03*
G54D26*
X197691Y73000D03*
X176431D03*
X197691Y91000D03*
X176431D03*
X1574870Y67000D03*
Y85000D03*
X1596130Y67000D03*
Y85000D03*
G54D81*
X1756037Y330540D03*
X1758399D03*
Y340776D03*
G54D72*
X1706100Y86500D03*
X1701100D03*
X1696100D03*
X1691100D03*
Y107300D03*
X1696100D03*
X1701100D03*
X1706100D03*
G54D18*
X126986Y145500D03*
Y136500D03*
Y127500D03*
Y163500D03*
Y154500D03*
X139584Y145500D03*
Y136500D03*
Y127500D03*
Y163500D03*
Y154500D03*
X1592701Y149000D03*
X1605299D03*
Y140000D03*
X1592701D03*
Y131000D03*
X1605299D03*
Y122000D03*
X1592701D03*
X1605299Y158000D03*
X1592701D03*
G54D63*
X1620960Y111232D03*
Y108082D03*
X1624940Y111232D03*
Y108082D03*
X1662000Y108425D03*
Y111575D03*
G54D27*
X191885Y119000D03*
X200685Y115000D03*
Y123000D03*
X490384Y325500D03*
X499184Y329500D03*
Y321500D03*
X1263100Y329500D03*
X1271900Y333500D03*
X1263100Y337500D03*
X1539900Y112500D03*
X1531100Y108500D03*
Y116500D03*
X1762100Y241500D03*
Y248500D03*
X1771100Y241500D03*
Y248500D03*
X1779600Y241500D03*
Y248500D03*
G54D45*
X559949Y116300D03*
X566065D03*
X559949Y249500D03*
X566065D03*
X1202335Y116300D03*
X1196219D03*
X1202335Y249500D03*
X1196219D03*
G54D36*
X240866Y15512D03*
X300866Y10197D03*
X1431417Y15512D03*
X1491417Y10197D03*
G54D90*
X1851457Y220433D03*
X1856772Y360433D03*
G54D54*
X802087Y145984D03*
X792087D03*
X802087Y135984D03*
X792087D03*
X802087Y180984D03*
X792087D03*
X802087Y170984D03*
X792087D03*
X802087Y200984D03*
X792087D03*
X802087Y230984D03*
X792087D03*
X802087Y220984D03*
X792087D03*
X802087Y265984D03*
X792087D03*
X802087Y255984D03*
X792087D03*
X822087Y145984D03*
X812087D03*
X822087Y135984D03*
X812087D03*
X822087Y180984D03*
X812087D03*
X822087Y170984D03*
X812087D03*
Y200984D03*
X822087Y230984D03*
X812087D03*
X822087Y220984D03*
X812087D03*
X822087Y265984D03*
X812087D03*
X822087Y255984D03*
X812087D03*
X920197Y145984D03*
X910197D03*
X920197Y135984D03*
X910197D03*
X920197Y180984D03*
X910197D03*
X920197Y170984D03*
X910197D03*
X920197Y200984D03*
X910197D03*
X920197Y230984D03*
X910197D03*
X920197Y220984D03*
X910197D03*
X920197Y265984D03*
X910197D03*
X920197Y255984D03*
X910197D03*
X940197Y145984D03*
X930197D03*
X940197Y135984D03*
X930197D03*
X940197Y180984D03*
X930197D03*
X940197Y170984D03*
X930197D03*
Y200984D03*
X940197Y230984D03*
X930197D03*
X940197Y220984D03*
X930197D03*
X940197Y265984D03*
X930197D03*
X940197Y255984D03*
X930197D03*
G54D91*
G01X156785Y110251D02*
Y101285D01*
G01X490384Y325500D02*
X495184D01*
X499184Y321500D01*
G01X490384Y325500D02*
X484100D01*
G01X485300Y332100D02*
X492700D01*
X495300Y329500D01*
X499184D01*
G01X515009Y322000D02*
X517409D01*
G01X609637Y254523D02*
X609514Y254400D01*
X604607D01*
X602203Y256804D01*
Y271913D01*
X597954Y276162D01*
Y284272D01*
X576422Y305804D01*
Y319778D01*
X572306Y323894D01*
X519303D01*
X517409Y322000D01*
G01X511859D02*
Y323626D01*
X510779Y324706D01*
X502390D01*
X499184Y321500D01*
G01X508709Y329000D02*
X506309D01*
G01X508709Y322000D02*
X506309D01*
G01X511859Y329000D02*
Y327206D01*
X510859Y326206D01*
X502478D01*
X499184Y329500D01*
G01X559949Y116300D02*
X561330D01*
X563007Y117977D01*
Y118477D01*
G01X566065Y116300D02*
X564830D01*
X563007Y114477D01*
Y114123D01*
G01Y251677D02*
Y251177D01*
X561330Y249500D01*
X559949D01*
G01X566065D02*
X564830D01*
X563007Y247677D01*
Y247323D01*
G01X1157138Y303000D02*
X1155600Y304538D01*
Y316243D01*
X1174357Y335000D01*
X1242875D01*
X1244875Y337000D01*
X1247275D01*
G01X1196219Y116300D02*
X1197600D01*
X1199277Y117977D01*
Y118477D01*
G01X1202335Y116300D02*
X1201100D01*
X1199277Y114477D01*
Y114123D01*
G01X1202335Y249500D02*
X1201100D01*
X1199277Y247677D01*
Y247323D01*
G01X1196219Y249500D02*
X1197600D01*
X1199277Y251177D01*
Y251677D01*
G01X1263100Y337500D02*
X1259894Y334294D01*
X1251505D01*
X1250425Y335374D01*
Y337000D01*
G01X1255975D02*
X1253575D01*
G01X1255975Y330000D02*
X1253575D01*
G01X1263100Y329500D02*
X1259806Y332794D01*
X1251425D01*
X1250425Y331794D01*
Y330000D01*
G01X1263100Y329500D02*
X1278200D01*
G01X1271900Y333500D02*
X1267100D01*
X1263100Y337500D01*
G01D02*
Y343200D01*
G01X1620960Y108082D02*
X1618900Y106022D01*
Y93701D01*
X1625701Y86900D01*
X1635000D01*
X1636500Y85400D01*
G01X1635470Y130850D02*
Y126640D01*
X1639963Y122147D01*
Y118712D01*
G01X1637994D02*
Y121141D01*
X1631770Y127365D01*
G01D02*
X1627770D01*
G01D02*
X1622388D01*
G01X1654615Y102380D02*
X1657050D01*
G01X1769300Y340600D02*
X1768349Y339649D01*
X1766249D01*
G01X1779816D02*
X1775816D01*
G01D02*
X1771816D01*
G01D02*
X1770251D01*
X1769300Y340600D01*
G01X1771735Y332322D02*
X1771282D01*
X1769692Y333912D01*
Y334649D01*
G54D46*
X561246Y155300D03*
Y287500D03*
X601516Y300000D03*
X663700Y256000D03*
X654200Y251500D03*
Y256000D03*
Y260500D03*
Y266000D03*
X663700Y251500D03*
X677616Y298500D03*
X659016Y322500D03*
X688516Y178500D03*
X727327Y300595D03*
X875116Y362000D03*
Y382000D03*
X1066616Y307500D03*
Y311500D03*
X1082616Y251500D03*
X1095616Y291500D03*
Y287500D03*
X1105116Y296000D03*
X1146516Y251500D03*
X1624786Y119140D03*
X1626516Y178000D03*
Y172500D03*
X1628516Y167500D03*
Y163500D03*
X1705016Y134500D03*
Y129500D03*
X1692516Y148000D03*
Y164500D03*
Y170000D03*
Y175500D03*
Y153500D03*
Y159000D03*
Y186500D03*
X1680516D03*
X1692516Y181000D03*
X1724216Y88000D03*
X1713216D03*
X1724216Y99000D03*
Y93500D03*
X1713216Y99000D03*
Y93500D03*
X1716016Y114500D03*
Y109500D03*
Y119500D03*
X1723016Y175000D03*
Y183500D03*
X1732016Y201500D03*
X1711116Y189500D03*
X1729016Y250000D03*
X1767516Y124500D03*
Y129500D03*
X1767016Y174000D03*
X1760016Y181500D03*
X1771796Y343970D03*
X1771916Y356300D03*
G36*
G01X834887Y88479D02*
G02X822087Y101284I-12800J5D01*
G02X834887Y88489I0J-12800D01*
G01X830387D01*
G03X822087Y80183I-8300J-5D01*
G03X830387Y88479I0J8301D01*
G01X834887D01*
G37*
G36*
G01Y313479D02*
G02X822087Y326284I-12800J5D01*
G02X834887Y313489I0J-12800D01*
G01X830387D01*
G03X822087Y305183I-8300J-5D01*
G03X830387Y313479I0J8301D01*
G01X834887D01*
G37*
G36*
G01X952997Y88479D02*
G02X940197Y101284I-12800J5D01*
G02X952997Y88489I0J-12800D01*
G01X948497D01*
G03X940197Y80183I-8300J-5D01*
G03X948497Y88479I0J8301D01*
G01X952997D01*
G37*
G36*
G01Y313479D02*
G02X940197Y326284I-12800J5D01*
G02X952997Y313489I0J-12800D01*
G01X948497D01*
G03X940197Y305183I-8300J-5D01*
G03X948497Y313479I0J8301D01*
G01X952997D01*
G37*
G54D73*
X1732100Y104500D03*
Y109500D03*
Y114500D03*
Y119500D03*
Y124500D03*
Y129500D03*
Y134500D03*
X1752900Y114500D03*
Y109500D03*
Y104500D03*
Y134500D03*
Y129500D03*
Y124500D03*
Y119500D03*
G54D19*
X134655Y120500D03*
X130915D03*
X1597630Y115000D03*
X1601370D03*
G54D28*
X190950Y106500D03*
X197250Y109059D03*
Y103941D03*
X1541150Y99500D03*
X1534850Y96941D03*
Y102059D03*
G54D64*
X1637601Y113200D03*
X1641144D03*
X1644687D03*
X1648231D03*
G54D82*
X1762533Y328965D03*
G54D37*
X287402Y628465D03*
X263780Y659961D03*
X668314Y570042D03*
X681498Y575042D03*
Y565042D03*
X668420Y598187D03*
X681604Y593187D03*
Y603187D03*
X1011017Y570042D03*
X997833Y575042D03*
Y565042D03*
X1011017Y598187D03*
X997833Y593187D03*
Y603187D03*
X1468504Y628465D03*
X1444882Y659961D03*
G54D92*
G01X1643500Y152925D02*
X1635000D01*
G01X1666500Y181075D02*
X1664167D01*
X1662969Y182273D01*
G01X1733711Y143661D02*
X1729411D01*
G01X1733711Y159161D02*
X1729411D01*
G01X1751289Y166839D02*
X1754339D01*
X1756000Y168500D01*
G01X1755979Y151339D02*
X1751289D01*
G54D47*
X564213Y155300D03*
Y287500D03*
X604483Y300000D03*
X666667Y256000D03*
X657167Y251500D03*
Y256000D03*
Y260500D03*
Y266000D03*
X666667Y251500D03*
X680583Y298500D03*
X661983Y322500D03*
X691483Y178500D03*
X730294Y300595D03*
X878083Y362000D03*
Y382000D03*
X1069583Y307500D03*
Y311500D03*
X1085583Y251500D03*
X1098583Y291500D03*
Y287500D03*
X1108083Y296000D03*
X1149483Y251500D03*
X1627753Y119140D03*
X1629483Y178000D03*
Y172500D03*
X1631483Y167500D03*
Y163500D03*
X1707983Y134500D03*
Y129500D03*
X1695483Y148000D03*
Y164500D03*
Y170000D03*
Y175500D03*
Y153500D03*
Y159000D03*
Y186500D03*
X1683483D03*
X1695483Y181000D03*
X1727183Y88000D03*
X1716183D03*
X1727183Y99000D03*
Y93500D03*
X1716183Y99000D03*
Y93500D03*
X1718983Y114500D03*
Y109500D03*
Y119500D03*
X1725983Y175000D03*
Y183500D03*
X1734983Y201500D03*
X1714083Y189500D03*
X1731983Y250000D03*
X1762983Y181500D03*
X1770483Y124500D03*
Y129500D03*
X1769983Y174000D03*
X1774763Y343970D03*
X1774883Y356300D03*
G54D38*
X387060Y55500D03*
X394540D03*
X590760Y318000D03*
X598240D03*
X696760Y178000D03*
X704240D03*
X1031840Y190500D03*
X1024360D03*
X1628840Y202500D03*
X1621360D03*
G54D56*
X822087Y88484D03*
Y313484D03*
X940197Y88484D03*
Y313484D03*
G54D74*
X1733711Y143661D03*
Y146220D03*
Y159161D03*
Y161720D03*
Y164280D03*
Y166839D03*
Y148780D03*
Y151339D03*
X1751289Y146220D03*
Y143661D03*
Y166839D03*
Y164280D03*
Y161720D03*
Y159161D03*
Y151339D03*
Y148780D03*
G54D29*
X192600Y130201D03*
Y142799D03*
X1539600Y123701D03*
Y136299D03*
G54D83*
X1751389Y357827D03*
X1758389D03*
X1751389Y350127D03*
X1758389D03*
X1765600Y370000D03*
Y363000D03*
X1751389Y365527D03*
X1758389D03*
X1751389Y373227D03*
X1758389D03*
X1772600Y370000D03*
Y363000D03*
G54D65*
X1634451Y111232D03*
Y115168D03*
G54D93*
G01X606084Y293100D02*
Y296165D01*
X604483Y297766D01*
Y299908D01*
X604575Y300000D01*
G01X1774983Y348288D02*
X1777383D01*
G54D48*
X631000Y313760D03*
Y321240D03*
G54D75*
X1737677Y177500D03*
Y173760D03*
Y181240D03*
X1747323Y173760D03*
Y181240D03*
G54D66*
X1647837Y107688D03*
X1645868D03*
X1643900D03*
X1641932D03*
X1639963D03*
X1637994D03*
X1636026D03*
Y118712D03*
X1637994D03*
X1639963D03*
X1641932D03*
X1643900D03*
X1645868D03*
X1647837D03*
X1651774Y107688D03*
X1649806D03*
Y118712D03*
G54D57*
X822087Y200984D03*
X940197D03*
G54D39*
X462338Y61900D03*
Y81900D03*
Y106300D03*
Y126300D03*
Y150700D03*
Y170700D03*
Y195100D03*
Y215100D03*
Y239500D03*
Y259500D03*
Y283900D03*
Y303900D03*
X1299946Y81900D03*
Y61900D03*
Y106300D03*
Y126300D03*
Y170700D03*
Y150700D03*
Y195100D03*
Y215100D03*
Y239500D03*
Y259500D03*
Y283900D03*
Y303900D03*
G54D84*
X1751706Y336741D03*
G54D94*
G01X162583Y225798D02*
X166785Y230000D01*
G01D02*
X170987Y234202D01*
G01X162583D02*
X166785Y230000D01*
G01D02*
X170987Y225798D01*
G01X162583Y305798D02*
X166785Y310000D01*
G01D02*
X170987Y314202D01*
G01X162583D02*
X166785Y310000D01*
G01D02*
X170987Y305798D01*
G01X162583Y385798D02*
X166785Y390000D01*
G01D02*
X170987Y394202D01*
G01X162583D02*
X166785Y390000D01*
G01D02*
X170987Y385798D01*
G01X162583Y465798D02*
X166785Y470000D01*
G01D02*
X170987Y474202D01*
G01X162583D02*
X166785Y470000D01*
G01D02*
X170987Y465798D01*
G01X162583Y545798D02*
X166785Y550000D01*
G01D02*
X170987Y554202D01*
G01X162583D02*
X166785Y550000D01*
G01D02*
X170987Y545798D01*
G01X239583Y225798D02*
X243785Y230000D01*
G01D02*
X247987Y234202D01*
G01X239583D02*
X243785Y230000D01*
G01D02*
X247987Y225798D01*
G01X239583Y305798D02*
X243785Y310000D01*
G01D02*
X247987Y314202D01*
G01X239583D02*
X243785Y310000D01*
G01D02*
X247987Y305798D01*
G01X239583Y385798D02*
X243785Y390000D01*
G01D02*
X247987Y394202D01*
G01X239583D02*
X243785Y390000D01*
G01D02*
X247987Y385798D01*
G01X239583Y465798D02*
X243785Y470000D01*
G01D02*
X247987Y474202D01*
G01X239583D02*
X243785Y470000D01*
G01D02*
X247987Y465798D01*
G01X239583Y545798D02*
X243785Y550000D01*
G01D02*
X247987Y554202D01*
G01X239583D02*
X243785Y550000D01*
G01D02*
X247987Y545798D01*
G01X1484298Y225798D02*
X1488500Y230000D01*
G01D02*
X1492702Y234202D01*
G01X1484298D02*
X1488500Y230000D01*
G01D02*
X1492702Y225798D01*
G01X1484298Y305798D02*
X1488500Y310000D01*
G01D02*
X1492702Y314202D01*
G01X1484298D02*
X1488500Y310000D01*
G01D02*
X1492702Y305798D01*
G01X1484298Y385798D02*
X1488500Y390000D01*
G01D02*
X1492702Y394202D01*
G01X1484298D02*
X1488500Y390000D01*
G01D02*
X1492702Y385798D01*
G01X1484298Y465798D02*
X1488500Y470000D01*
G01D02*
X1492702Y474202D01*
G01X1484298D02*
X1488500Y470000D01*
G01D02*
X1492702Y465798D01*
G01X1484298Y545798D02*
X1488500Y550000D01*
G01D02*
X1492702Y554202D01*
G01X1484298D02*
X1488500Y550000D01*
G01D02*
X1492702Y545798D01*
G01X1561298Y225798D02*
X1565500Y230000D01*
G01D02*
X1569702Y234202D01*
G01X1561298D02*
X1565500Y230000D01*
G01D02*
X1569702Y225798D01*
G01X1561298Y305798D02*
X1565500Y310000D01*
G01D02*
X1569702Y314202D01*
G01X1561298D02*
X1565500Y310000D01*
G01D02*
X1569702Y305798D01*
G01X1561298Y385798D02*
X1565500Y390000D01*
G01D02*
X1569702Y394202D01*
G01X1561298D02*
X1565500Y390000D01*
G01D02*
X1569702Y385798D01*
G01X1561298Y465798D02*
X1565500Y470000D01*
G01D02*
X1569702Y474202D01*
G01X1561298D02*
X1565500Y470000D01*
G01D02*
X1569702Y465798D01*
G01X1561298Y545798D02*
X1565500Y550000D01*
G01D02*
X1569702Y554202D01*
G01X1561298D02*
X1565500Y550000D01*
G01D02*
X1569702Y545798D01*
G54D76*
X1731000Y241630D03*
Y245370D03*
G54D49*
X643941Y324740D03*
X649059D03*
Y317260D03*
X646500D03*
X643941D03*
X725559Y305260D03*
X720441D03*
Y312740D03*
X723000D03*
X725559D03*
G54D58*
X825900Y362200D03*
X866400Y382200D03*
X906900Y362200D03*
G54D67*
G01X134655Y120500D02*
X137355D01*
G01X197250Y109059D02*
X200600D01*
G01X200685Y123000D02*
X205100D01*
G01X444838Y87700D02*
X441938D01*
G01Y132100D02*
X444838D01*
G01Y176500D02*
X441938D01*
G01X444838Y220900D02*
X441938D01*
G01X444838Y265300D02*
X441938D01*
G01X444838Y309700D02*
X441938D01*
G01X618500Y333500D02*
X588000D01*
X580994Y326494D01*
X519916D01*
X517410Y329000D01*
G01X515009D02*
X517410D01*
G01X557230Y135300D02*
X561330D01*
X562830Y136800D01*
G01X557230Y142300D02*
X561330D01*
X562830Y143800D01*
G01X551430Y142300D02*
Y149300D01*
G01Y142300D02*
Y135300D01*
G01D02*
Y132400D01*
G01X557230Y149300D02*
X560626D01*
X561626Y150300D01*
Y154829D01*
X561155Y155300D01*
G01X551430Y268500D02*
Y265600D01*
G01Y275500D02*
Y268500D01*
G01X562830Y266500D02*
X562666D01*
X560666Y268500D01*
X557230D01*
G01X551430Y282500D02*
Y275500D01*
G01X557230Y282500D02*
X560576D01*
X561576Y283500D01*
Y287079D01*
X561155Y287500D01*
G01X562830Y273500D02*
X562696D01*
X560696Y275500D01*
X557230D01*
G01X568430Y135300D02*
X564958D01*
X562958Y133300D01*
X562830D01*
G01Y140300D02*
X562996D01*
X564996Y142300D01*
X568430D01*
G01X574230Y149300D02*
Y142300D01*
G01D02*
Y135300D01*
G01D02*
Y132400D01*
G01X561155Y155300D02*
Y160784D01*
G01X568430Y149300D02*
X564927D01*
X563927Y150300D01*
Y154922D01*
X564305Y155300D01*
G01D02*
Y160784D01*
G01X574230Y275500D02*
Y268500D01*
G01D02*
Y267837D01*
X576467Y265600D01*
G01X568430Y268500D02*
X564330D01*
X562830Y270000D01*
G01X574230Y282500D02*
Y275500D01*
G01X568430D02*
X564330D01*
X562830Y277000D01*
G01X571325Y292757D02*
X571047Y292479D01*
X564780D01*
X561155Y288854D01*
Y287500D01*
G01X568430Y282500D02*
X564889D01*
X563889Y283500D01*
Y287084D01*
X564305Y287500D01*
G01X571542Y289065D02*
X570982Y289625D01*
X565836D01*
X564305Y288094D01*
Y287500D01*
G01X590760Y318000D02*
Y313876D01*
X590684Y313800D01*
G01X601675Y305575D02*
X601425Y305325D01*
Y300000D01*
G01X616684Y307975D02*
Y305803D01*
X612797Y301916D01*
X608172Y300000D01*
X604575D01*
G01X616684Y307975D02*
X622159D01*
X622184Y308000D01*
G01X671000Y331925D02*
X669976Y332949D01*
Y345711D01*
X662239Y353448D01*
X628000D01*
X622558Y348006D01*
Y332059D01*
X619999Y329500D01*
X609740D01*
X598240Y318000D01*
G01X654109Y251500D02*
X650100D01*
G01X649500Y260575D02*
Y264400D01*
X651100Y266000D01*
G01X654109Y260500D02*
X649575D01*
X649500Y260575D01*
G01X641100Y251500D02*
Y254468D01*
X647116Y260484D01*
X649409D01*
X649500Y260575D01*
G01X637684Y280575D02*
Y292500D01*
X622184Y308000D01*
G01X643941Y324740D02*
X649276Y330075D01*
X653500D01*
G01X649059Y317260D02*
Y314000D01*
G01X632186Y338917D02*
Y322426D01*
X631000Y321240D01*
G01X663609Y260500D02*
X662684D01*
X660684Y262500D01*
G01X663609Y264500D02*
X662684D01*
X660684Y262500D01*
G01X654109Y256000D02*
Y260500D01*
G01Y266000D02*
X651100D01*
G01X662075Y322500D02*
Y320000D01*
G01X675100Y304500D02*
X677100Y302500D01*
X677525D01*
G01X674276Y315760D02*
X671000D01*
G01X668000Y311500D02*
Y315100D01*
G01X663500Y311500D02*
Y314425D01*
G01X653500Y326925D02*
X657500D01*
G01X680500Y331925D02*
Y328404D01*
X683724Y325180D01*
Y323240D01*
G01X653500Y330075D02*
X657500D01*
G01X680500Y331925D02*
X676500D01*
G01D02*
X671000D01*
G01X688425Y178500D02*
Y183785D01*
X688900Y184260D01*
G01X682163D02*
X688900D01*
G01X693863Y189760D02*
X697163D01*
G01X734500Y307425D02*
Y304709D01*
X730386Y300595D01*
G01X732000Y307425D02*
X727724D01*
X725559Y305260D01*
G01X734500Y307425D02*
X732000D01*
G01X719500Y315500D02*
X720441Y314559D01*
Y312740D01*
G01X732000Y310575D02*
X734500D01*
G01X1043360Y197437D02*
Y193760D01*
X1041675Y192075D01*
X1037600D01*
G01X1030100Y207500D02*
X1032360Y205240D01*
X1036937D01*
G01D02*
X1043360Y198817D01*
Y197437D01*
G01X1066525Y307500D02*
X1065100D01*
X1062600Y305000D01*
G01X1066525Y311500D02*
Y307500D01*
G01X1100100Y243500D02*
X1093675D01*
X1085675Y251500D01*
G01X1100500Y263500D02*
X1103000Y261000D01*
Y245300D01*
X1101200Y243500D01*
X1100100D01*
G01X1098675Y287500D02*
X1099600D01*
X1101600Y289500D01*
G01X1098675Y291500D02*
X1099600D01*
X1101600Y289500D01*
G01X1105025Y296000D02*
X1102600D01*
G01X1108175Y291500D02*
X1111100D01*
G01X1108175Y285000D02*
X1111100D01*
G01X1118175Y296000D02*
X1121100D01*
G01X1108175Y300500D02*
X1111100D01*
G01X1120400D02*
Y301100D01*
X1118000Y303500D01*
G01X1146425Y251500D02*
X1143500D01*
G01X1156200Y258900D02*
Y255825D01*
X1151875Y251500D01*
X1149575D01*
G01X1145600Y244025D02*
X1140125D01*
X1140100Y244000D01*
G01X1145600Y244025D02*
X1149575Y248000D01*
Y251500D01*
G01X1157800Y312050D02*
Y314200D01*
G01D02*
X1175600Y332000D01*
X1242874D01*
X1244874Y330000D01*
G01X1168200Y349700D02*
X1162425Y343925D01*
Y340500D01*
G01X1187700Y135300D02*
Y132400D01*
G01Y142300D02*
Y135300D01*
G01Y149300D02*
Y142300D01*
G01X1193500D02*
X1197600D01*
X1199100Y143800D01*
G01X1193500Y135300D02*
X1197600D01*
X1199100Y136800D01*
G01X1197425Y155300D02*
X1197853Y154872D01*
Y150300D01*
X1196853Y149300D01*
X1193500D01*
G01X1187700Y275500D02*
Y268500D01*
G01D02*
Y265600D01*
G01X1199100Y266500D02*
X1198932D01*
X1196932Y268500D01*
X1193500D01*
G01X1187700Y282500D02*
Y275500D01*
G01Y282500D02*
Y288000D01*
G01X1193500Y282500D02*
X1196820D01*
X1197820Y283500D01*
Y288105D01*
X1197425Y288500D01*
G01X1199100Y273500D02*
X1198966D01*
X1196966Y275500D01*
X1193500D01*
G01X1168200Y349700D02*
X1170700Y347200D01*
X1173200D01*
X1176000Y350000D01*
G01D02*
X1171000Y355000D01*
X1167800D01*
G01X1210500Y135300D02*
Y132400D01*
G01Y142300D02*
Y135300D01*
G01Y149300D02*
Y142300D01*
G01X1204700D02*
X1201232D01*
X1199232Y140300D01*
X1199100D01*
G01Y133300D02*
X1199276D01*
X1201276Y135300D01*
X1204700D01*
G01X1200575Y155300D02*
X1200179Y154904D01*
Y150300D01*
X1201179Y149300D01*
X1204700D01*
G01X1200575Y160284D02*
Y155300D01*
G01X1197425Y160284D02*
Y155300D01*
G01X1210500Y275500D02*
Y268500D01*
G01D02*
Y265600D01*
G01X1199100Y270000D02*
X1200600Y268500D01*
X1204700D01*
G01X1210500Y282500D02*
Y275500D01*
G01X1196500Y293284D02*
X1197425Y292359D01*
Y288500D01*
G01X1204700Y282500D02*
X1201159D01*
X1200159Y283500D01*
Y288084D01*
X1200575Y288500D01*
G01X1201500Y293284D02*
X1200575Y292359D01*
Y288500D01*
G01X1199100Y277000D02*
X1199900D01*
X1201400Y275500D01*
X1204700D01*
G01X1247275Y330000D02*
X1244874D01*
G01X1317446Y67900D02*
X1320346D01*
G01X1317446Y112300D02*
X1320346D01*
G01X1317446Y156700D02*
X1320346D01*
G01X1317446Y201100D02*
X1320346D01*
G01X1317446Y245500D02*
X1320346D01*
G01X1317446Y289900D02*
X1320346D01*
G01X1531100Y108500D02*
X1527100D01*
G01X1534850Y96941D02*
X1531600D01*
G01X1597630Y115000D02*
X1594930D01*
G01X1612425Y173000D02*
Y180924D01*
X1617076Y185575D01*
X1618500D01*
G01X1612425Y173000D02*
Y169500D01*
G01D02*
Y165500D01*
G01X1626425Y172500D02*
X1623100D01*
G01X1626425Y178000D02*
X1623100D01*
G01X1635340Y149063D02*
Y152585D01*
X1635000Y152925D01*
G01X1618500Y185575D02*
X1621424D01*
X1623999Y183000D01*
X1626425D01*
G01X1686860Y202240D02*
X1686100Y203000D01*
Y206500D01*
X1684525Y208075D01*
X1653075D01*
X1639624Y194624D01*
Y185625D01*
X1637928Y183929D01*
X1632511D01*
X1631055Y185385D01*
X1627912D01*
X1626425Y183898D01*
Y183000D01*
G01X1631585Y188777D02*
X1633646D01*
X1635163Y187260D01*
G01X1652600Y212000D02*
X1646124D01*
X1641000Y206876D01*
Y204575D01*
G01X1662000Y108425D02*
Y106000D01*
G01X1662969Y182273D02*
Y185227D01*
X1664242Y186500D01*
X1664925D01*
G01D02*
Y191325D01*
X1666199Y192599D01*
X1672501D01*
X1674100Y191000D01*
X1684600D01*
X1686100Y192500D01*
Y201480D01*
X1686860Y202240D01*
G01X1668075Y189500D02*
Y186500D01*
G01X1685100Y121825D02*
Y115600D01*
X1691100Y109600D01*
Y107300D01*
G01X1682500Y121825D02*
X1685100D01*
G01X1695575Y148000D02*
X1697976D01*
G01X1690100Y124975D02*
Y127375D01*
G01X1704925Y134500D02*
Y129500D01*
G01D02*
X1702525D01*
G01X1683575Y148000D02*
X1685976D01*
G01X1690100Y135975D02*
X1692600D01*
G01X1685100Y124975D02*
Y127500D01*
G01X1695575Y164500D02*
X1697976D01*
G01X1695575Y159000D02*
X1697976D01*
G01X1695575Y175500D02*
X1697976D01*
G01X1695575Y170000D02*
X1697976D01*
G01X1695575Y153500D02*
X1697976D01*
G01X1683575Y164500D02*
X1685976D01*
G01X1683575Y159000D02*
X1685976D01*
G01X1683575Y153500D02*
X1685976D01*
G01X1683575Y175500D02*
X1685976D01*
G01X1683575Y170000D02*
X1685976D01*
G01X1695575Y181000D02*
X1697975D01*
G01X1704600Y201500D02*
X1703600Y200500D01*
X1695240D01*
X1693500Y202240D01*
X1686860D01*
G01X1683575Y181000D02*
X1685976D01*
G01X1702925Y208000D02*
X1702075Y207150D01*
Y205500D01*
G01X1716275Y88000D02*
X1718675D01*
G01X1716275Y99000D02*
X1718675D01*
G01X1716275Y93500D02*
X1718675D01*
G01X1715925Y109500D02*
X1713524D01*
G01X1715925Y114500D02*
X1713524D01*
G01X1732100Y104500D02*
X1727200D01*
G01X1715925Y134500D02*
X1713525D01*
G01X1717100Y144925D02*
Y140600D01*
X1713525Y137025D01*
Y134500D01*
G01X1715925Y129500D02*
X1713525D01*
G01X1715925Y119500D02*
X1713524D01*
G01X1722925Y175000D02*
X1720524D01*
G01X1716500Y160425D02*
Y159100D01*
X1717600Y158000D01*
G01X1737677Y173760D02*
X1733500D01*
G01X1731925Y201500D02*
Y199000D01*
G01X1715376Y194760D02*
Y190701D01*
X1714175Y189500D01*
G01D02*
Y187000D01*
G01X1724824Y202240D02*
Y205276D01*
G01X1711025Y189500D02*
Y187000D01*
G01X1722925Y179500D02*
X1720100D01*
G01X1729000Y183500D02*
X1726075D01*
G01X1738740Y188063D02*
Y191500D01*
G01X1767425Y134500D02*
Y137000D01*
G01X1752900Y134500D02*
X1767425D01*
G01X1768500Y144925D02*
Y142525D01*
G01Y160425D02*
Y158025D01*
G01X1756000Y168500D02*
X1763925D01*
G01D02*
Y170984D01*
G01Y153000D02*
Y155484D01*
G01Y153000D02*
X1757640D01*
X1755979Y151339D01*
G01X1767075Y153000D02*
Y155484D01*
G01Y168500D02*
X1769476D01*
G01X1759925Y181500D02*
Y178900D01*
G01X1747323Y181240D02*
X1757364D01*
X1757624Y181500D01*
X1759925D01*
G01X1754925Y200500D02*
Y203000D01*
G01X1763075Y181500D02*
Y178900D01*
G01X1750563Y187260D02*
X1754260D01*
G01X1764563D02*
X1768000D01*
G01X1762454Y322905D02*
Y320347D01*
G01X1770575Y109500D02*
X1772975D01*
G01X1770575Y104500D02*
X1772975D01*
G01X1773076Y117500D02*
X1772076Y116500D01*
X1770675D01*
G01X1770575Y134500D02*
Y137000D01*
G01X1770075Y174000D02*
X1772500D01*
G01X1769425Y200500D02*
Y203000D01*
G01X1790100Y247500D02*
X1791600D01*
X1793100Y249000D01*
Y253075D01*
G01X1790100Y247500D02*
X1789600Y247000D01*
G01X1793100Y253075D02*
Y325499D01*
X1782100Y336499D01*
X1779816D01*
G01X1774975Y356300D02*
X1777375D01*
G01X1779816Y336499D02*
X1775816D01*
G01X1774983Y352305D02*
X1777383D01*
X1642915Y111950D03*
X1639372Y114450D03*
X1646458Y111950D03*
X1642915Y114450D03*
X1639372Y111950D03*
X1646458Y114450D03*
X1650002Y111950D03*
Y114450D03*
G54D85*
X1762730Y340382D03*
Y338808D03*
Y337233D03*
Y335658D03*
Y334083D03*
Y332508D03*
Y330934D03*
G54D95*
G01X-457143Y-1211429D02*
Y2242857D01*
X4308572D01*
Y-1211429D01*
X-457143D01*
G01X37000Y-995000D02*
Y-1070000D01*
X537000D01*
Y-995000D01*
X37000D01*
G01X49000Y-1060000D02*
Y-1065000D01*
G01X47543Y-1060000D02*
X50457D01*
G01X55367Y-1065000D02*
X52833D01*
Y-1060000D01*
X55367D01*
G01X54353Y-1062417D02*
X52833D01*
G01X57933Y-1060000D02*
Y-1065000D01*
X60467D01*
G01X64300Y-1065167D02*
X64173Y-1065083D01*
Y-1064917D01*
X64300Y-1064833D01*
X64427Y-1064917D01*
Y-1065083D01*
X64300Y-1065167D01*
G01Y-1062917D02*
X64173Y-1062833D01*
Y-1062667D01*
X64300Y-1062583D01*
X64427Y-1062667D01*
Y-1062833D01*
X64300Y-1062917D01*
G01X69083Y-1066667D02*
X68450Y-1065833D01*
X68133Y-1065000D01*
Y-1061667D01*
X68450Y-1060833D01*
X69083Y-1060000D01*
G01X74500D02*
X73993Y-1060167D01*
X73613Y-1060583D01*
X73360Y-1061083D01*
X73170Y-1061750D01*
X73107Y-1062500D01*
X73170Y-1063250D01*
X73360Y-1063917D01*
X73613Y-1064417D01*
X73993Y-1064833D01*
X74500Y-1065000D01*
X75007Y-1064833D01*
X75387Y-1064417D01*
X75640Y-1063917D01*
X75830Y-1063250D01*
X75893Y-1062500D01*
X75830Y-1061750D01*
X75640Y-1061083D01*
X75387Y-1060583D01*
X75007Y-1060167D01*
X74500Y-1060000D01*
G01X78207Y-1064000D02*
X78587Y-1064583D01*
X79093Y-1064917D01*
X79663Y-1065000D01*
X80170Y-1064917D01*
X80677Y-1064500D01*
X80993Y-1064000D01*
X81057Y-1063500D01*
X80930Y-1062917D01*
X80487Y-1062500D01*
X80043Y-1062333D01*
X79473D01*
G01X80043D02*
X80423Y-1062083D01*
X80740Y-1061667D01*
X80867Y-1061167D01*
X80740Y-1060667D01*
X80423Y-1060250D01*
X79853Y-1060000D01*
X79283Y-1060083D01*
X78713Y-1060417D01*
G01X85017Y-1066667D02*
X85650Y-1065833D01*
X85967Y-1065000D01*
Y-1061667D01*
X85650Y-1060833D01*
X85017Y-1060000D01*
G01X88407Y-1064000D02*
X88787Y-1064583D01*
X89293Y-1064917D01*
X89863Y-1065000D01*
X90370Y-1064917D01*
X90877Y-1064500D01*
X91193Y-1064000D01*
X91257Y-1063500D01*
X91130Y-1062917D01*
X90687Y-1062500D01*
X90243Y-1062333D01*
X89673D01*
G01X90243D02*
X90623Y-1062083D01*
X90940Y-1061667D01*
X91067Y-1061167D01*
X90940Y-1060667D01*
X90623Y-1060250D01*
X90053Y-1060000D01*
X89483Y-1060083D01*
X88913Y-1060417D01*
G01X93697Y-1060833D02*
X94077Y-1060333D01*
X94520Y-1060083D01*
X95027Y-1060000D01*
X95660Y-1060167D01*
X96103Y-1060583D01*
X96230Y-1061083D01*
X96167Y-1061583D01*
X95913Y-1062000D01*
X94647Y-1062833D01*
X94077Y-1063417D01*
X93697Y-1064250D01*
X93570Y-1065000D01*
X96230D01*
G01X99873D02*
X100000Y-1063917D01*
X100190Y-1063000D01*
X100443Y-1062167D01*
X100760Y-1061250D01*
X101267Y-1060000D01*
X98733D01*
G01X104277Y-1063333D02*
X105923D01*
G01X108997Y-1060833D02*
X109377Y-1060333D01*
X109820Y-1060083D01*
X110327Y-1060000D01*
X110960Y-1060167D01*
X111403Y-1060583D01*
X111530Y-1061083D01*
X111467Y-1061583D01*
X111213Y-1062000D01*
X109947Y-1062833D01*
X109377Y-1063417D01*
X108997Y-1064250D01*
X108870Y-1065000D01*
X111530D01*
G01X113907Y-1064000D02*
X114287Y-1064583D01*
X114793Y-1064917D01*
X115363Y-1065000D01*
X115870Y-1064917D01*
X116377Y-1064500D01*
X116693Y-1064000D01*
X116757Y-1063500D01*
X116630Y-1062917D01*
X116187Y-1062500D01*
X115743Y-1062333D01*
X115173D01*
G01X115743D02*
X116123Y-1062083D01*
X116440Y-1061667D01*
X116567Y-1061167D01*
X116440Y-1060667D01*
X116123Y-1060250D01*
X115553Y-1060000D01*
X114983Y-1060083D01*
X114413Y-1060417D01*
G01X121160Y-1065000D02*
Y-1060000D01*
X118817Y-1063583D01*
X121983D01*
G01X124107Y-1064250D02*
X124487Y-1064667D01*
X124930Y-1064917D01*
X125500Y-1065000D01*
X126070Y-1064833D01*
X126513Y-1064500D01*
X126830Y-1063917D01*
X126893Y-1063250D01*
X126767Y-1062583D01*
X126450Y-1062167D01*
X126007Y-1061833D01*
X125563Y-1061750D01*
X125120Y-1061833D01*
X124550Y-1062167D01*
X124740Y-1060000D01*
X126450D01*
G01X134497Y-1065000D02*
Y-1060000D01*
X136903D01*
G01X136017Y-1062417D02*
X134497D01*
G01X139217Y-1065000D02*
X140800Y-1060000D01*
X142383Y-1065000D01*
G01X141813Y-1063250D02*
X139787D01*
G01X144570Y-1065000D02*
X147230Y-1060000D01*
G01X144570D02*
X147230Y-1065000D01*
G01X151000Y-1065167D02*
X150873Y-1065083D01*
Y-1064917D01*
X151000Y-1064833D01*
X151127Y-1064917D01*
Y-1065083D01*
X151000Y-1065167D01*
G01Y-1062917D02*
X150873Y-1062833D01*
Y-1062667D01*
X151000Y-1062583D01*
X151127Y-1062667D01*
Y-1062833D01*
X151000Y-1062917D01*
G01X155783Y-1066667D02*
X155150Y-1065833D01*
X154833Y-1065000D01*
Y-1061667D01*
X155150Y-1060833D01*
X155783Y-1060000D01*
G01X161200D02*
X160693Y-1060167D01*
X160313Y-1060583D01*
X160060Y-1061083D01*
X159870Y-1061750D01*
X159807Y-1062500D01*
X159870Y-1063250D01*
X160060Y-1063917D01*
X160313Y-1064417D01*
X160693Y-1064833D01*
X161200Y-1065000D01*
X161707Y-1064833D01*
X162087Y-1064417D01*
X162340Y-1063917D01*
X162530Y-1063250D01*
X162593Y-1062500D01*
X162530Y-1061750D01*
X162340Y-1061083D01*
X162087Y-1060583D01*
X161707Y-1060167D01*
X161200Y-1060000D01*
G01X164907Y-1064000D02*
X165287Y-1064583D01*
X165793Y-1064917D01*
X166363Y-1065000D01*
X166870Y-1064917D01*
X167377Y-1064500D01*
X167693Y-1064000D01*
X167757Y-1063500D01*
X167630Y-1062917D01*
X167187Y-1062500D01*
X166743Y-1062333D01*
X166173D01*
G01X166743D02*
X167123Y-1062083D01*
X167440Y-1061667D01*
X167567Y-1061167D01*
X167440Y-1060667D01*
X167123Y-1060250D01*
X166553Y-1060000D01*
X165983Y-1060083D01*
X165413Y-1060417D01*
G01X171717Y-1066667D02*
X172350Y-1065833D01*
X172667Y-1065000D01*
Y-1061667D01*
X172350Y-1060833D01*
X171717Y-1060000D01*
G01X175107Y-1064000D02*
X175487Y-1064583D01*
X175993Y-1064917D01*
X176563Y-1065000D01*
X177070Y-1064917D01*
X177577Y-1064500D01*
X177893Y-1064000D01*
X177957Y-1063500D01*
X177830Y-1062917D01*
X177387Y-1062500D01*
X176943Y-1062333D01*
X176373D01*
G01X176943D02*
X177323Y-1062083D01*
X177640Y-1061667D01*
X177767Y-1061167D01*
X177640Y-1060667D01*
X177323Y-1060250D01*
X176753Y-1060000D01*
X176183Y-1060083D01*
X175613Y-1060417D01*
G01X180523Y-1064417D02*
X180967Y-1064833D01*
X181473Y-1065000D01*
X181980Y-1064833D01*
X182423Y-1064333D01*
X182740Y-1063583D01*
X182867Y-1062833D01*
Y-1061917D01*
X182740Y-1061167D01*
X182423Y-1060500D01*
X182043Y-1060167D01*
X181600Y-1060000D01*
X181093Y-1060167D01*
X180713Y-1060500D01*
X180460Y-1061000D01*
X180333Y-1061667D01*
X180460Y-1062250D01*
X180777Y-1062833D01*
X181157Y-1063167D01*
X181600Y-1063250D01*
X182107Y-1063083D01*
X182487Y-1062667D01*
X182867Y-1061917D01*
G01X186573Y-1065000D02*
X186700Y-1063917D01*
X186890Y-1063000D01*
X187143Y-1062167D01*
X187460Y-1061250D01*
X187967Y-1060000D01*
X185433D01*
G01X190977Y-1063333D02*
X192623D01*
G01X195507Y-1064000D02*
X195887Y-1064583D01*
X196393Y-1064917D01*
X196963Y-1065000D01*
X197470Y-1064917D01*
X197977Y-1064500D01*
X198293Y-1064000D01*
X198357Y-1063500D01*
X198230Y-1062917D01*
X197787Y-1062500D01*
X197343Y-1062333D01*
X196773D01*
G01X197343D02*
X197723Y-1062083D01*
X198040Y-1061667D01*
X198167Y-1061167D01*
X198040Y-1060667D01*
X197723Y-1060250D01*
X197153Y-1060000D01*
X196583Y-1060083D01*
X196013Y-1060417D01*
G01X200797Y-1062917D02*
X201240Y-1062333D01*
X201620Y-1062000D01*
X202127Y-1061833D01*
X202570Y-1062000D01*
X202887Y-1062333D01*
X203140Y-1062833D01*
X203203Y-1063417D01*
X203140Y-1063917D01*
X202887Y-1064417D01*
X202507Y-1064833D01*
X202063Y-1065000D01*
X201557Y-1064833D01*
X201113Y-1064333D01*
X200860Y-1063583D01*
X200797Y-1062750D01*
X200923Y-1061667D01*
X201113Y-1061083D01*
X201430Y-1060500D01*
X201873Y-1060083D01*
X202317Y-1060000D01*
X202760Y-1060167D01*
X203077Y-1060583D01*
G01X207100Y-1065000D02*
Y-1060000D01*
X206340Y-1061000D01*
G01Y-1065000D02*
X207860D01*
G01X212960D02*
Y-1060000D01*
X210617Y-1063583D01*
X213783D01*
G01X232000Y-995000D02*
Y-1070000D01*
G01Y-1045000D02*
X335000D01*
Y-1020000D01*
G01X232000D02*
X335000D01*
G01X337000Y-995000D02*
Y-1070000D01*
G01X335000Y-995000D02*
Y-1070000D01*
G01X342507Y-1055000D02*
Y-1050000D01*
X343773D01*
X344280Y-1050250D01*
X344660Y-1050583D01*
X344977Y-1051083D01*
X345230Y-1051667D01*
X345293Y-1052500D01*
X345230Y-1053333D01*
X344977Y-1053917D01*
X344660Y-1054417D01*
X344280Y-1054750D01*
X343773Y-1055000D01*
X342507D01*
G01X347417D02*
X349000Y-1050000D01*
X350583Y-1055000D01*
G01X350013Y-1053250D02*
X347987D01*
G01X354100Y-1050000D02*
Y-1055000D01*
G01X352643Y-1050000D02*
X355557D01*
G01X360467Y-1055000D02*
X357933D01*
Y-1050000D01*
X360467D01*
G01X359453Y-1052417D02*
X357933D01*
G01X364300Y-1055167D02*
X364173Y-1055083D01*
Y-1054917D01*
X364300Y-1054833D01*
X364427Y-1054917D01*
Y-1055083D01*
X364300Y-1055167D01*
G01Y-1052917D02*
X364173Y-1052833D01*
Y-1052667D01*
X364300Y-1052583D01*
X364427Y-1052667D01*
Y-1052833D01*
X364300Y-1052917D01*
G01X337000Y-1045000D02*
X537000D01*
G01X342633Y-1030000D02*
Y-1025000D01*
X344153D01*
X344660Y-1025250D01*
X345040Y-1025833D01*
X345167Y-1026500D01*
X345040Y-1027167D01*
X344723Y-1027667D01*
X344153Y-1027917D01*
X342633D01*
G01X347860Y-1030167D02*
X350140Y-1025000D01*
G01X352643Y-1030000D02*
Y-1025000D01*
X355557Y-1030000D01*
Y-1025000D01*
G01X359200Y-1030167D02*
X359073Y-1030083D01*
Y-1029917D01*
X359200Y-1029833D01*
X359327Y-1029917D01*
Y-1030083D01*
X359200Y-1030167D01*
G01Y-1027917D02*
X359073Y-1027833D01*
Y-1027667D01*
X359200Y-1027583D01*
X359327Y-1027667D01*
Y-1027833D01*
X359200Y-1027917D01*
G01X342633Y-1005000D02*
Y-1000000D01*
X344153D01*
X344660Y-1000250D01*
X345040Y-1000833D01*
X345167Y-1001500D01*
X345040Y-1002167D01*
X344723Y-1002667D01*
X344153Y-1002917D01*
X342633D01*
G01X347733Y-1005000D02*
Y-1000000D01*
X349317D01*
X349823Y-1000250D01*
X350140Y-1000583D01*
X350267Y-1001250D01*
X350140Y-1001917D01*
X349760Y-1002333D01*
X349317Y-1002583D01*
X347733D01*
G01X349317D02*
X350267Y-1005000D01*
G01X354100D02*
X353593Y-1004917D01*
X353150Y-1004583D01*
X352770Y-1004083D01*
X352517Y-1003500D01*
X352390Y-1002833D01*
Y-1002167D01*
X352517Y-1001500D01*
X352770Y-1000917D01*
X353150Y-1000417D01*
X353593Y-1000083D01*
X354100Y-1000000D01*
X354607Y-1000083D01*
X355050Y-1000417D01*
X355430Y-1000917D01*
X355683Y-1001500D01*
X355810Y-1002167D01*
Y-1002833D01*
X355683Y-1003500D01*
X355430Y-1004083D01*
X355050Y-1004583D01*
X354607Y-1004917D01*
X354100Y-1005000D01*
G01X357933Y-1004000D02*
X358250Y-1004500D01*
X358630Y-1004833D01*
X359073Y-1005000D01*
X359580Y-1004833D01*
X359960Y-1004500D01*
X360340Y-1004000D01*
X360467Y-1003333D01*
Y-1000000D01*
G01X365567Y-1005000D02*
X363033D01*
Y-1000000D01*
X365567D01*
G01X364553Y-1002417D02*
X363033D01*
G01X370793Y-1000417D02*
X370413Y-1000167D01*
X369970Y-1000000D01*
X369463D01*
X368893Y-1000250D01*
X368450Y-1000667D01*
X368133Y-1001167D01*
X367880Y-1002000D01*
X367817Y-1002750D01*
X367943Y-1003500D01*
X368133Y-1004000D01*
X368513Y-1004500D01*
X368957Y-1004833D01*
X369400Y-1005000D01*
X369843D01*
X370287Y-1004833D01*
X370667Y-1004583D01*
X370983Y-1004250D01*
G01X374500Y-1000000D02*
Y-1005000D01*
G01X373043Y-1000000D02*
X375957D01*
G01X379600Y-1005167D02*
X379473Y-1005083D01*
Y-1004917D01*
X379600Y-1004833D01*
X379727Y-1004917D01*
Y-1005083D01*
X379600Y-1005167D01*
G01Y-1002917D02*
X379473Y-1002833D01*
Y-1002667D01*
X379600Y-1002583D01*
X379727Y-1002667D01*
Y-1002833D01*
X379600Y-1002917D01*
G01X337000Y-1020000D02*
X537000D01*
G01X452000Y-1045000D02*
Y-1070000D01*
G01X454633Y-1047500D02*
Y-1052500D01*
X457167D01*
G01X460240Y-1047500D02*
X461760D01*
G01X461000D02*
Y-1052500D01*
G01X460240D02*
X461760D01*
G01X466607Y-1049833D02*
X466860Y-1049583D01*
X467050Y-1049167D01*
X467177Y-1048583D01*
X467050Y-1048083D01*
X466797Y-1047750D01*
X466353Y-1047500D01*
X464643D01*
Y-1052500D01*
X466733D01*
X467177Y-1052167D01*
X467430Y-1051667D01*
X467557Y-1051083D01*
X467430Y-1050500D01*
X467050Y-1050000D01*
X466607Y-1049833D01*
X464643D01*
G01X471200Y-1052667D02*
X471073Y-1052583D01*
Y-1052417D01*
X471200Y-1052333D01*
X471327Y-1052417D01*
Y-1052583D01*
X471200Y-1052667D01*
G01Y-1050417D02*
X471073Y-1050333D01*
Y-1050167D01*
X471200Y-1050083D01*
X471327Y-1050167D01*
Y-1050333D01*
X471200Y-1050417D01*
G01X495000Y-1045000D02*
Y-1070000D01*
G01X498900Y-1047500D02*
Y-1052500D01*
G01X497443Y-1047500D02*
X500357D01*
G01X504000Y-1052500D02*
X503620Y-1052417D01*
X503240Y-1052083D01*
X502987Y-1051500D01*
X502860Y-1050833D01*
X502987Y-1050167D01*
X503240Y-1049583D01*
X503620Y-1049250D01*
X504000Y-1049167D01*
X504380Y-1049250D01*
X504760Y-1049583D01*
X505013Y-1050167D01*
X505077Y-1050833D01*
X505013Y-1051500D01*
X504760Y-1052083D01*
X504380Y-1052417D01*
X504000Y-1052500D01*
G01X509100D02*
X508720Y-1052417D01*
X508340Y-1052083D01*
X508087Y-1051500D01*
X507960Y-1050833D01*
X508087Y-1050167D01*
X508340Y-1049583D01*
X508720Y-1049250D01*
X509100Y-1049167D01*
X509480Y-1049250D01*
X509860Y-1049583D01*
X510113Y-1050167D01*
X510177Y-1050833D01*
X510113Y-1051500D01*
X509860Y-1052083D01*
X509480Y-1052417D01*
X509100Y-1052500D01*
G01X514200D02*
Y-1047500D01*
G01X519300Y-1052667D02*
X519173Y-1052583D01*
Y-1052417D01*
X519300Y-1052333D01*
X519427Y-1052417D01*
Y-1052583D01*
X519300Y-1052667D01*
G01Y-1050417D02*
X519173Y-1050333D01*
Y-1050167D01*
X519300Y-1050083D01*
X519427Y-1050167D01*
Y-1050333D01*
X519300Y-1050417D01*
G01X495000Y-1020000D02*
Y-1045000D01*
G01X497633Y-1027500D02*
Y-1022500D01*
X499217D01*
X499723Y-1022750D01*
X500040Y-1023083D01*
X500167Y-1023750D01*
X500040Y-1024417D01*
X499660Y-1024833D01*
X499217Y-1025083D01*
X497633D01*
G01X499217D02*
X500167Y-1027500D01*
G01X505267D02*
X502733D01*
Y-1022500D01*
X505267D01*
G01X504253Y-1024917D02*
X502733D01*
G01X507517Y-1022500D02*
X509100Y-1027500D01*
X510683Y-1022500D01*
G01X514200Y-1027667D02*
X514073Y-1027583D01*
Y-1027417D01*
X514200Y-1027333D01*
X514327Y-1027417D01*
Y-1027583D01*
X514200Y-1027667D01*
G01Y-1025417D02*
X514073Y-1025333D01*
Y-1025167D01*
X514200Y-1025083D01*
X514327Y-1025167D01*
Y-1025333D01*
X514200Y-1025417D01*
G01X503013Y-1073167D02*
X503120Y-1073042D01*
X503200Y-1072833D01*
X503253Y-1072542D01*
X503200Y-1072292D01*
X503093Y-1072125D01*
X502907Y-1072000D01*
X502187D01*
Y-1074500D01*
X503067D01*
X503253Y-1074333D01*
X503360Y-1074083D01*
X503413Y-1073792D01*
X503360Y-1073500D01*
X503200Y-1073250D01*
X503013Y-1073167D01*
X502187D01*
G01X505480Y-1074500D02*
Y-1072833D01*
G01Y-1073125D02*
X505373Y-1072958D01*
X505213Y-1072875D01*
X505027Y-1072833D01*
X504840Y-1072917D01*
X504680Y-1073083D01*
X504573Y-1073333D01*
X504520Y-1073667D01*
X504573Y-1074000D01*
X504680Y-1074250D01*
X504840Y-1074417D01*
X505027Y-1074500D01*
X505213Y-1074458D01*
X505373Y-1074333D01*
X505480Y-1074167D01*
G01X506800Y-1074208D02*
X506933Y-1074375D01*
X507120Y-1074500D01*
X507280D01*
X507440Y-1074417D01*
X507547Y-1074292D01*
X507600Y-1074125D01*
X507573Y-1073875D01*
X507467Y-1073750D01*
X506987Y-1073500D01*
X506880Y-1073208D01*
X506933Y-1073000D01*
X507040Y-1072875D01*
X507200Y-1072833D01*
X507360Y-1072875D01*
X507520Y-1073000D01*
G01X509000Y-1073375D02*
X509853D01*
X509773Y-1073083D01*
X509640Y-1072917D01*
X509453Y-1072833D01*
X509267Y-1072875D01*
X509107Y-1073000D01*
X509000Y-1073292D01*
X508947Y-1073542D01*
Y-1073792D01*
X509000Y-1074042D01*
X509133Y-1074292D01*
X509293Y-1074458D01*
X509480Y-1074500D01*
X509667Y-1074417D01*
X509853Y-1074167D01*
G01X511120Y-1074500D02*
Y-1072000D01*
G01Y-1073250D02*
X511253Y-1073000D01*
X511413Y-1072875D01*
X511573Y-1072833D01*
X511813Y-1072917D01*
X511973Y-1073083D01*
X512080Y-1073375D01*
Y-1073708D01*
X512027Y-1074042D01*
X511920Y-1074292D01*
X511733Y-1074458D01*
X511573Y-1074500D01*
X511413Y-1074458D01*
X511253Y-1074333D01*
X511120Y-1074125D01*
G01X513800Y-1074500D02*
X513640Y-1074458D01*
X513480Y-1074292D01*
X513373Y-1074000D01*
X513320Y-1073667D01*
X513373Y-1073333D01*
X513480Y-1073042D01*
X513640Y-1072875D01*
X513800Y-1072833D01*
X513960Y-1072875D01*
X514120Y-1073042D01*
X514227Y-1073333D01*
X514253Y-1073667D01*
X514227Y-1074000D01*
X514120Y-1074292D01*
X513960Y-1074458D01*
X513800Y-1074500D01*
G01X516480D02*
Y-1072833D01*
G01Y-1073125D02*
X516373Y-1072958D01*
X516213Y-1072875D01*
X516027Y-1072833D01*
X515840Y-1072917D01*
X515680Y-1073083D01*
X515573Y-1073333D01*
X515520Y-1073667D01*
X515573Y-1074000D01*
X515680Y-1074250D01*
X515840Y-1074417D01*
X516027Y-1074500D01*
X516213Y-1074458D01*
X516373Y-1074333D01*
X516480Y-1074167D01*
G01X517827Y-1074500D02*
Y-1072833D01*
G01Y-1073167D02*
X517960Y-1073000D01*
X518093Y-1072875D01*
X518280Y-1072833D01*
X518413Y-1072875D01*
X518573Y-1073000D01*
G01X520880Y-1072000D02*
Y-1074500D01*
G01Y-1074125D02*
X520773Y-1074333D01*
X520613Y-1074458D01*
X520427Y-1074500D01*
X520213Y-1074417D01*
X520053Y-1074208D01*
X519947Y-1073958D01*
X519920Y-1073667D01*
X519947Y-1073375D01*
X520053Y-1073125D01*
X520213Y-1072917D01*
X520427Y-1072833D01*
X520613Y-1072875D01*
X520747Y-1072958D01*
X520880Y-1073125D01*
G01X524267Y-1074500D02*
Y-1072000D01*
X524933D01*
X525147Y-1072125D01*
X525280Y-1072292D01*
X525333Y-1072625D01*
X525280Y-1072958D01*
X525120Y-1073167D01*
X524933Y-1073292D01*
X524267D01*
G01X524933D02*
X525333Y-1074500D01*
G01X526600Y-1073375D02*
X527453D01*
X527373Y-1073083D01*
X527240Y-1072917D01*
X527053Y-1072833D01*
X526867Y-1072875D01*
X526707Y-1073000D01*
X526600Y-1073292D01*
X526547Y-1073542D01*
Y-1073792D01*
X526600Y-1074042D01*
X526733Y-1074292D01*
X526893Y-1074458D01*
X527080Y-1074500D01*
X527267Y-1074417D01*
X527453Y-1074167D01*
G01X528720Y-1072833D02*
X529200Y-1074500D01*
X529680Y-1072833D01*
G01X531400Y-1074583D02*
X531347Y-1074542D01*
Y-1074458D01*
X531400Y-1074417D01*
X531453Y-1074458D01*
Y-1074542D01*
X531400Y-1074583D01*
G01X533600Y-1074500D02*
X533787Y-1074458D01*
X534000Y-1074333D01*
X534133Y-1074125D01*
X534187Y-1073833D01*
X534133Y-1073542D01*
X533973Y-1073292D01*
X533733Y-1073167D01*
X533467D01*
X533307Y-1073083D01*
X533173Y-1072875D01*
X533120Y-1072583D01*
X533200Y-1072292D01*
X533387Y-1072083D01*
X533600Y-1072000D01*
X533813Y-1072083D01*
X534000Y-1072292D01*
X534080Y-1072583D01*
X534027Y-1072875D01*
X533893Y-1073083D01*
X533733Y-1073167D01*
X533467D01*
X533227Y-1073292D01*
X533067Y-1073542D01*
X533013Y-1073833D01*
X533067Y-1074125D01*
X533200Y-1074333D01*
X533413Y-1074458D01*
X533600Y-1074500D01*
G01X536013Y-1073167D02*
X536120Y-1073042D01*
X536200Y-1072833D01*
X536253Y-1072542D01*
X536200Y-1072292D01*
X536093Y-1072125D01*
X535907Y-1072000D01*
X535187D01*
Y-1074500D01*
X536067D01*
X536253Y-1074333D01*
X536360Y-1074083D01*
X536413Y-1073792D01*
X536360Y-1073500D01*
X536200Y-1073250D01*
X536013Y-1073167D01*
X535187D01*
G01X-457143Y-1211429D02*
Y2242857D01*
X4308572D01*
Y-1211429D01*
X-457143D01*
G01X71650Y-1024800D02*
X69130Y-1024383D01*
X66925Y-1022717D01*
X65035Y-1020217D01*
X63775Y-1017300D01*
X63145Y-1013967D01*
Y-1010633D01*
X63775Y-1007300D01*
X65035Y-1004383D01*
X66925Y-1001884D01*
X69130Y-1000217D01*
X71650Y-999800D01*
X74170Y-1000217D01*
X76375Y-1001884D01*
X78265Y-1004383D01*
X79525Y-1007300D01*
X80155Y-1010633D01*
Y-1013967D01*
X79525Y-1017300D01*
X78265Y-1020217D01*
X76375Y-1022717D01*
X74170Y-1024383D01*
X71650Y-1024800D01*
G01X74170Y-1018133D02*
X77950Y-1024800D01*
G01X91495Y-1008134D02*
Y-1019800D01*
X92755Y-1022717D01*
X94645Y-1024383D01*
X96850Y-1024800D01*
X99055Y-1024383D01*
X100945Y-1022717D01*
X102205Y-1019800D01*
G01Y-1024800D02*
Y-1008134D01*
G01X127720Y-1024800D02*
Y-1008134D01*
G01Y-1011050D02*
X126460Y-1009384D01*
X124570Y-1008550D01*
X122365Y-1008134D01*
X120160Y-1008967D01*
X118270Y-1010633D01*
X117010Y-1013134D01*
X116380Y-1016467D01*
X117010Y-1019800D01*
X118270Y-1022301D01*
X120160Y-1023967D01*
X122365Y-1024800D01*
X124570Y-1024383D01*
X126460Y-1023134D01*
X127720Y-1021467D01*
G01X141895Y-1024800D02*
Y-1008134D01*
G01Y-1012300D02*
X143155Y-1010217D01*
X145045Y-1008550D01*
X147565Y-1008134D01*
X149770Y-1008550D01*
X151660Y-1010217D01*
X152605Y-1013134D01*
Y-1024800D01*
G01X172450Y-999800D02*
Y-1024800D01*
G01X168040Y-1008134D02*
X176860D01*
G01X203320Y-1024800D02*
Y-1008134D01*
G01Y-1011050D02*
X202060Y-1009384D01*
X200170Y-1008550D01*
X197965Y-1008134D01*
X195760Y-1008967D01*
X193870Y-1010633D01*
X192610Y-1013134D01*
X191980Y-1016467D01*
X192610Y-1019800D01*
X193870Y-1022301D01*
X195760Y-1023967D01*
X197965Y-1024800D01*
X200170Y-1024383D01*
X202060Y-1023134D01*
X203320Y-1021467D01*
G01X49820Y-1042350D02*
X51387D01*
Y-1044240D01*
X50917Y-1044870D01*
X50368Y-1045290D01*
X49585Y-1045500D01*
X48802Y-1045290D01*
X48253Y-1044870D01*
X47783Y-1044240D01*
X47470Y-1043505D01*
X47313Y-1042665D01*
Y-1041930D01*
X47470Y-1041300D01*
X47783Y-1040565D01*
X48253Y-1039935D01*
X48723Y-1039515D01*
X49350Y-1039200D01*
X49898D01*
X50525Y-1039410D01*
X50995Y-1039830D01*
G01X53927Y-1039200D02*
Y-1043715D01*
X54240Y-1044660D01*
X54867Y-1045290D01*
X55650Y-1045500D01*
X56433Y-1045290D01*
X57060Y-1044660D01*
X57373Y-1043715D01*
Y-1039200D01*
G01X61010D02*
X62890D01*
G01X61950D02*
Y-1045500D01*
G01X61010D02*
X62890D01*
G01X66605Y-1044660D02*
X67232Y-1045185D01*
X67937Y-1045500D01*
X68563D01*
X69190Y-1045185D01*
X69660Y-1044660D01*
X69895Y-1043925D01*
X69738Y-1043190D01*
X69347Y-1042560D01*
X68642Y-1042140D01*
X67702Y-1041930D01*
X67153Y-1041510D01*
X66918Y-1040775D01*
X67075Y-1040040D01*
X67467Y-1039515D01*
X68015Y-1039200D01*
X68563D01*
X69112Y-1039410D01*
X69582Y-1039935D01*
G01X72905Y-1045500D02*
Y-1039200D01*
G01X76195D02*
Y-1045500D01*
G01Y-1042350D02*
X72905D01*
G01X78892Y-1045500D02*
X80850Y-1039200D01*
X82808Y-1045500D01*
G01X82103Y-1043295D02*
X79597D01*
G01X85348Y-1045500D02*
Y-1039200D01*
X88952Y-1045500D01*
Y-1039200D01*
G01X98027Y-1045500D02*
Y-1039200D01*
X99593D01*
X100220Y-1039515D01*
X100690Y-1039935D01*
X101082Y-1040565D01*
X101395Y-1041300D01*
X101473Y-1042350D01*
X101395Y-1043400D01*
X101082Y-1044135D01*
X100690Y-1044765D01*
X100220Y-1045185D01*
X99593Y-1045500D01*
X98027D01*
G01X105110Y-1039200D02*
X106990D01*
G01X106050D02*
Y-1045500D01*
G01X105110D02*
X106990D01*
G01X110705Y-1044660D02*
X111332Y-1045185D01*
X112037Y-1045500D01*
X112663D01*
X113290Y-1045185D01*
X113760Y-1044660D01*
X113995Y-1043925D01*
X113838Y-1043190D01*
X113447Y-1042560D01*
X112742Y-1042140D01*
X111802Y-1041930D01*
X111253Y-1041510D01*
X111018Y-1040775D01*
X111175Y-1040040D01*
X111567Y-1039515D01*
X112115Y-1039200D01*
X112663D01*
X113212Y-1039410D01*
X113682Y-1039935D01*
G01X118650Y-1039200D02*
Y-1045500D01*
G01X116848Y-1039200D02*
X120452D01*
G01X124950Y-1045710D02*
X124793Y-1045605D01*
Y-1045395D01*
X124950Y-1045290D01*
X125107Y-1045395D01*
Y-1045605D01*
X124950Y-1045710D01*
G01X131093Y-1046655D02*
X131407Y-1045290D01*
G01X137550Y-1039200D02*
Y-1045500D01*
G01X135748Y-1039200D02*
X139352D01*
G01X141892Y-1045500D02*
X143850Y-1039200D01*
X145808Y-1045500D01*
G01X145103Y-1043295D02*
X142597D01*
G01X150150Y-1045500D02*
X149523Y-1045395D01*
X148975Y-1044975D01*
X148505Y-1044345D01*
X148192Y-1043610D01*
X148035Y-1042770D01*
Y-1041930D01*
X148192Y-1041090D01*
X148505Y-1040355D01*
X148975Y-1039725D01*
X149523Y-1039305D01*
X150150Y-1039200D01*
X150777Y-1039305D01*
X151325Y-1039725D01*
X151795Y-1040355D01*
X152108Y-1041090D01*
X152265Y-1041930D01*
Y-1042770D01*
X152108Y-1043610D01*
X151795Y-1044345D01*
X151325Y-1044975D01*
X150777Y-1045395D01*
X150150Y-1045500D01*
G01X156450D02*
Y-1042665D01*
X154883Y-1039200D01*
G01X158017D02*
X156450Y-1042665D01*
G01X161027Y-1039200D02*
Y-1043715D01*
X161340Y-1044660D01*
X161967Y-1045290D01*
X162750Y-1045500D01*
X163533Y-1045290D01*
X164160Y-1044660D01*
X164473Y-1043715D01*
Y-1039200D01*
G01X167092Y-1045500D02*
X169050Y-1039200D01*
X171008Y-1045500D01*
G01X170303Y-1043295D02*
X167797D01*
G01X173548Y-1045500D02*
Y-1039200D01*
X177152Y-1045500D01*
Y-1039200D01*
G01X51073Y-1049725D02*
X50603Y-1049410D01*
X50055Y-1049200D01*
X49428D01*
X48723Y-1049515D01*
X48175Y-1050040D01*
X47783Y-1050670D01*
X47470Y-1051720D01*
X47392Y-1052665D01*
X47548Y-1053610D01*
X47783Y-1054240D01*
X48253Y-1054870D01*
X48802Y-1055290D01*
X49350Y-1055500D01*
X49898D01*
X50447Y-1055290D01*
X50917Y-1054975D01*
X51308Y-1054555D01*
G01X54710Y-1049200D02*
X56590D01*
G01X55650D02*
Y-1055500D01*
G01X54710D02*
X56590D01*
G01X61950Y-1049200D02*
Y-1055500D01*
G01X60148Y-1049200D02*
X63752D01*
G01X68250Y-1055500D02*
Y-1052665D01*
X66683Y-1049200D01*
G01X69817D02*
X68250Y-1052665D01*
G01X79127Y-1054240D02*
X79597Y-1054975D01*
X80223Y-1055395D01*
X80928Y-1055500D01*
X81555Y-1055395D01*
X82182Y-1054870D01*
X82573Y-1054240D01*
X82652Y-1053610D01*
X82495Y-1052875D01*
X81947Y-1052350D01*
X81398Y-1052140D01*
X80693D01*
G01X81398D02*
X81868Y-1051825D01*
X82260Y-1051300D01*
X82417Y-1050670D01*
X82260Y-1050040D01*
X81868Y-1049515D01*
X81163Y-1049200D01*
X80458Y-1049305D01*
X79753Y-1049725D01*
G01X85427Y-1054240D02*
X85897Y-1054975D01*
X86523Y-1055395D01*
X87228Y-1055500D01*
X87855Y-1055395D01*
X88482Y-1054870D01*
X88873Y-1054240D01*
X88952Y-1053610D01*
X88795Y-1052875D01*
X88247Y-1052350D01*
X87698Y-1052140D01*
X86993D01*
G01X87698D02*
X88168Y-1051825D01*
X88560Y-1051300D01*
X88717Y-1050670D01*
X88560Y-1050040D01*
X88168Y-1049515D01*
X87463Y-1049200D01*
X86758Y-1049305D01*
X86053Y-1049725D01*
G01X91727Y-1054240D02*
X92197Y-1054975D01*
X92823Y-1055395D01*
X93528Y-1055500D01*
X94155Y-1055395D01*
X94782Y-1054870D01*
X95173Y-1054240D01*
X95252Y-1053610D01*
X95095Y-1052875D01*
X94547Y-1052350D01*
X93998Y-1052140D01*
X93293D01*
G01X93998D02*
X94468Y-1051825D01*
X94860Y-1051300D01*
X95017Y-1050670D01*
X94860Y-1050040D01*
X94468Y-1049515D01*
X93763Y-1049200D01*
X93058Y-1049305D01*
X92353Y-1049725D01*
G01X99593Y-1055500D02*
X99750Y-1054135D01*
X99985Y-1052980D01*
X100298Y-1051930D01*
X100690Y-1050775D01*
X101317Y-1049200D01*
X98183D01*
G01X105893Y-1055500D02*
X106050Y-1054135D01*
X106285Y-1052980D01*
X106598Y-1051930D01*
X106990Y-1050775D01*
X107617Y-1049200D01*
X104483D01*
G01X112193Y-1056655D02*
X112507Y-1055290D01*
G01X118650Y-1049200D02*
Y-1055500D01*
G01X116848Y-1049200D02*
X120452D01*
G01X122992Y-1055500D02*
X124950Y-1049200D01*
X126908Y-1055500D01*
G01X126203Y-1053295D02*
X123697D01*
G01X130310Y-1049200D02*
X132190D01*
G01X131250D02*
Y-1055500D01*
G01X130310D02*
X132190D01*
G01X135200Y-1049200D02*
X136297Y-1055500D01*
X137550Y-1049200D01*
X138803Y-1055500D01*
X139900Y-1049200D01*
G01X141892Y-1055500D02*
X143850Y-1049200D01*
X145808Y-1055500D01*
G01X145103Y-1053295D02*
X142597D01*
G01X148348Y-1055500D02*
Y-1049200D01*
X151952Y-1055500D01*
Y-1049200D01*
G01X162358Y-1057600D02*
X161575Y-1056550D01*
X161183Y-1055500D01*
Y-1051300D01*
X161575Y-1050250D01*
X162358Y-1049200D01*
G01X173783Y-1055500D02*
Y-1049200D01*
X175742D01*
X176368Y-1049515D01*
X176760Y-1049935D01*
X176917Y-1050775D01*
X176760Y-1051615D01*
X176290Y-1052140D01*
X175742Y-1052455D01*
X173783D01*
G01X175742D02*
X176917Y-1055500D01*
G01X181650Y-1055710D02*
X181493Y-1055605D01*
Y-1055395D01*
X181650Y-1055290D01*
X181807Y-1055395D01*
Y-1055605D01*
X181650Y-1055710D01*
G01X187950Y-1055500D02*
X187323Y-1055395D01*
X186775Y-1054975D01*
X186305Y-1054345D01*
X185992Y-1053610D01*
X185835Y-1052770D01*
Y-1051930D01*
X185992Y-1051090D01*
X186305Y-1050355D01*
X186775Y-1049725D01*
X187323Y-1049305D01*
X187950Y-1049200D01*
X188577Y-1049305D01*
X189125Y-1049725D01*
X189595Y-1050355D01*
X189908Y-1051090D01*
X190065Y-1051930D01*
Y-1052770D01*
X189908Y-1053610D01*
X189595Y-1054345D01*
X189125Y-1054975D01*
X188577Y-1055395D01*
X187950Y-1055500D01*
G01X194250Y-1055710D02*
X194093Y-1055605D01*
Y-1055395D01*
X194250Y-1055290D01*
X194407Y-1055395D01*
Y-1055605D01*
X194250Y-1055710D01*
G01X202273Y-1049725D02*
X201803Y-1049410D01*
X201255Y-1049200D01*
X200628D01*
X199923Y-1049515D01*
X199375Y-1050040D01*
X198983Y-1050670D01*
X198670Y-1051720D01*
X198592Y-1052665D01*
X198748Y-1053610D01*
X198983Y-1054240D01*
X199453Y-1054870D01*
X200002Y-1055290D01*
X200550Y-1055500D01*
X201098D01*
X201647Y-1055290D01*
X202117Y-1054975D01*
X202508Y-1054555D01*
G01X206850Y-1055710D02*
X206693Y-1055605D01*
Y-1055395D01*
X206850Y-1055290D01*
X207007Y-1055395D01*
Y-1055605D01*
X206850Y-1055710D01*
G01X213542Y-1057600D02*
X214325Y-1056550D01*
X214717Y-1055500D01*
Y-1051300D01*
X214325Y-1050250D01*
X213542Y-1049200D01*
G01X47548Y-1035500D02*
Y-1029200D01*
X51152Y-1035500D01*
Y-1029200D01*
G01X55650Y-1035500D02*
X55023Y-1035395D01*
X54475Y-1034975D01*
X54005Y-1034345D01*
X53692Y-1033610D01*
X53535Y-1032770D01*
Y-1031930D01*
X53692Y-1031090D01*
X54005Y-1030355D01*
X54475Y-1029725D01*
X55023Y-1029305D01*
X55650Y-1029200D01*
X56277Y-1029305D01*
X56825Y-1029725D01*
X57295Y-1030355D01*
X57608Y-1031090D01*
X57765Y-1031930D01*
Y-1032770D01*
X57608Y-1033610D01*
X57295Y-1034345D01*
X56825Y-1034975D01*
X56277Y-1035395D01*
X55650Y-1035500D01*
G01X61950Y-1035710D02*
X61793Y-1035605D01*
Y-1035395D01*
X61950Y-1035290D01*
X62107Y-1035395D01*
Y-1035605D01*
X61950Y-1035710D01*
G01X66762Y-1030250D02*
X67232Y-1029620D01*
X67780Y-1029305D01*
X68407Y-1029200D01*
X69190Y-1029410D01*
X69738Y-1029935D01*
X69895Y-1030565D01*
X69817Y-1031195D01*
X69503Y-1031720D01*
X67937Y-1032770D01*
X67232Y-1033505D01*
X66762Y-1034555D01*
X66605Y-1035500D01*
X69895D01*
G01X74550D02*
Y-1029200D01*
X73610Y-1030460D01*
G01Y-1035500D02*
X75490D01*
G01X80850D02*
Y-1029200D01*
X79910Y-1030460D01*
G01Y-1035500D02*
X81790D01*
G01X86993Y-1036655D02*
X87307Y-1035290D01*
G01X91100Y-1029200D02*
X92197Y-1035500D01*
X93450Y-1029200D01*
X94703Y-1035500D01*
X95800Y-1029200D01*
G01X101317Y-1035500D02*
X98183D01*
Y-1029200D01*
X101317D01*
G01X100063Y-1032245D02*
X98183D01*
G01X104248Y-1035500D02*
Y-1029200D01*
X107852Y-1035500D01*
Y-1029200D01*
G01X110705Y-1035500D02*
Y-1029200D01*
G01X113995D02*
Y-1035500D01*
G01Y-1032350D02*
X110705D01*
G01X116927Y-1029200D02*
Y-1033715D01*
X117240Y-1034660D01*
X117867Y-1035290D01*
X118650Y-1035500D01*
X119433Y-1035290D01*
X120060Y-1034660D01*
X120373Y-1033715D01*
Y-1029200D01*
G01X122992Y-1035500D02*
X124950Y-1029200D01*
X126908Y-1035500D01*
G01X126203Y-1033295D02*
X123697D01*
G01X136062Y-1030250D02*
X136532Y-1029620D01*
X137080Y-1029305D01*
X137707Y-1029200D01*
X138490Y-1029410D01*
X139038Y-1029935D01*
X139195Y-1030565D01*
X139117Y-1031195D01*
X138803Y-1031720D01*
X137237Y-1032770D01*
X136532Y-1033505D01*
X136062Y-1034555D01*
X135905Y-1035500D01*
X139195D01*
G01X142048D02*
Y-1029200D01*
X145652Y-1035500D01*
Y-1029200D01*
G01X148427Y-1035500D02*
Y-1029200D01*
X149993D01*
X150620Y-1029515D01*
X151090Y-1029935D01*
X151482Y-1030565D01*
X151795Y-1031300D01*
X151873Y-1032350D01*
X151795Y-1033400D01*
X151482Y-1034135D01*
X151090Y-1034765D01*
X150620Y-1035185D01*
X149993Y-1035500D01*
X148427D01*
G01X161183D02*
Y-1029200D01*
X163142D01*
X163768Y-1029515D01*
X164160Y-1029935D01*
X164317Y-1030775D01*
X164160Y-1031615D01*
X163690Y-1032140D01*
X163142Y-1032455D01*
X161183D01*
G01X163142D02*
X164317Y-1035500D01*
G01X167327D02*
Y-1029200D01*
X168893D01*
X169520Y-1029515D01*
X169990Y-1029935D01*
X170382Y-1030565D01*
X170695Y-1031300D01*
X170773Y-1032350D01*
X170695Y-1033400D01*
X170382Y-1034135D01*
X169990Y-1034765D01*
X169520Y-1035185D01*
X168893Y-1035500D01*
X167327D01*
G01X175350Y-1035710D02*
X175193Y-1035605D01*
Y-1035395D01*
X175350Y-1035290D01*
X175507Y-1035395D01*
Y-1035605D01*
X175350Y-1035710D01*
G01X243000Y-1004500D02*
Y-1012500D01*
X247000D01*
G01X254800D02*
Y-1007167D01*
G01Y-1008100D02*
X254400Y-1007567D01*
X253800Y-1007300D01*
X253100Y-1007167D01*
X252400Y-1007433D01*
X251800Y-1007967D01*
X251400Y-1008767D01*
X251200Y-1009833D01*
X251400Y-1010900D01*
X251800Y-1011700D01*
X252400Y-1012233D01*
X253100Y-1012500D01*
X253800Y-1012367D01*
X254400Y-1011967D01*
X254800Y-1011434D01*
G01X258900Y-1014900D02*
X259500Y-1015167D01*
X260300Y-1014900D01*
X260800Y-1014367D01*
X261200Y-1013700D01*
X261800Y-1011567D01*
X263100Y-1007167D01*
G01X259900D02*
X261800Y-1011567D01*
G01X267500Y-1008900D02*
X270700D01*
X270400Y-1007967D01*
X269900Y-1007433D01*
X269200Y-1007167D01*
X268500Y-1007300D01*
X267900Y-1007700D01*
X267500Y-1008633D01*
X267300Y-1009434D01*
Y-1010233D01*
X267500Y-1011033D01*
X268000Y-1011833D01*
X268600Y-1012367D01*
X269300Y-1012500D01*
X270000Y-1012233D01*
X270700Y-1011434D01*
G01X275600Y-1012500D02*
Y-1007167D01*
G01Y-1008233D02*
X276100Y-1007700D01*
X276600Y-1007300D01*
X277300Y-1007167D01*
X277800Y-1007300D01*
X278400Y-1007700D01*
G01X262100Y-1054500D02*
X265900D01*
X262100Y-1062500D01*
X265900D01*
G01X272000Y-1057167D02*
Y-1062500D01*
G01Y-1055033D02*
X271800Y-1054900D01*
Y-1054633D01*
X272000Y-1054500D01*
X272200Y-1054633D01*
Y-1054900D01*
X272000Y-1055033D01*
G01X278700Y-1059833D02*
X281300D01*
G01X286200Y-1065167D02*
Y-1057167D01*
G01Y-1058367D02*
X286700Y-1057700D01*
X287200Y-1057300D01*
X288000Y-1057167D01*
X288700Y-1057300D01*
X289400Y-1057967D01*
X289700Y-1058900D01*
X289800Y-1059833D01*
X289700Y-1060767D01*
X289400Y-1061700D01*
X288800Y-1062233D01*
X288000Y-1062500D01*
X287300Y-1062367D01*
X286600Y-1061967D01*
X286200Y-1061434D01*
G01X296000Y-1057167D02*
Y-1062500D01*
G01Y-1055033D02*
X295800Y-1054900D01*
Y-1054633D01*
X296000Y-1054500D01*
X296200Y-1054633D01*
Y-1054900D01*
X296000Y-1055033D01*
G01X302300Y-1062500D02*
Y-1057167D01*
G01Y-1058500D02*
X302700Y-1057833D01*
X303300Y-1057300D01*
X304100Y-1057167D01*
X304800Y-1057300D01*
X305400Y-1057833D01*
X305700Y-1058767D01*
Y-1062500D01*
G01X310600Y-1064500D02*
X311300Y-1065033D01*
X312100Y-1065167D01*
X312800Y-1065033D01*
X313400Y-1064367D01*
X313800Y-1063433D01*
Y-1057167D01*
G01Y-1058233D02*
X313400Y-1057700D01*
X312800Y-1057300D01*
X312100Y-1057167D01*
X311300Y-1057433D01*
X310800Y-1057967D01*
X310400Y-1058900D01*
X310200Y-1059833D01*
X310300Y-1060633D01*
X310700Y-1061567D01*
X311300Y-1062233D01*
X312100Y-1062500D01*
X312700Y-1062367D01*
X313400Y-1061833D01*
X313800Y-1061300D01*
G01X276500Y-1029500D02*
Y-1037500D01*
G01X274200Y-1029500D02*
X278800D01*
G01X284500Y-1037500D02*
X283700Y-1037367D01*
X283000Y-1036833D01*
X282400Y-1036033D01*
X282000Y-1035100D01*
X281800Y-1034033D01*
Y-1032967D01*
X282000Y-1031900D01*
X282400Y-1030967D01*
X283000Y-1030167D01*
X283700Y-1029633D01*
X284500Y-1029500D01*
X285300Y-1029633D01*
X286000Y-1030167D01*
X286600Y-1030967D01*
X287000Y-1031900D01*
X287200Y-1032967D01*
Y-1034033D01*
X287000Y-1035100D01*
X286600Y-1036033D01*
X286000Y-1036833D01*
X285300Y-1037367D01*
X284500Y-1037500D01*
G01X290500D02*
Y-1029500D01*
X292900D01*
X293700Y-1029900D01*
X294300Y-1030833D01*
X294500Y-1031900D01*
X294300Y-1032967D01*
X293800Y-1033767D01*
X292900Y-1034167D01*
X290500D01*
G01X296500Y-1012500D02*
Y-1004500D01*
X295300Y-1006100D01*
G01Y-1012500D02*
X297700D01*
G01X369600Y-1055833D02*
X370200Y-1055033D01*
X370900Y-1054633D01*
X371700Y-1054500D01*
X372700Y-1054767D01*
X373400Y-1055433D01*
X373600Y-1056233D01*
X373500Y-1057034D01*
X373100Y-1057700D01*
X371100Y-1059033D01*
X370200Y-1059967D01*
X369600Y-1061300D01*
X369400Y-1062500D01*
X373600D01*
G01X379500Y-1054500D02*
X378700Y-1054767D01*
X378100Y-1055433D01*
X377700Y-1056233D01*
X377400Y-1057300D01*
X377300Y-1058500D01*
X377400Y-1059700D01*
X377700Y-1060767D01*
X378100Y-1061567D01*
X378700Y-1062233D01*
X379500Y-1062500D01*
X380300Y-1062233D01*
X380900Y-1061567D01*
X381300Y-1060767D01*
X381600Y-1059700D01*
X381700Y-1058500D01*
X381600Y-1057300D01*
X381300Y-1056233D01*
X380900Y-1055433D01*
X380300Y-1054767D01*
X379500Y-1054500D01*
G01X385600Y-1055833D02*
X386200Y-1055033D01*
X386900Y-1054633D01*
X387700Y-1054500D01*
X388700Y-1054767D01*
X389400Y-1055433D01*
X389600Y-1056233D01*
X389500Y-1057034D01*
X389100Y-1057700D01*
X387100Y-1059033D01*
X386200Y-1059967D01*
X385600Y-1061300D01*
X385400Y-1062500D01*
X389600D01*
G01X393600Y-1055833D02*
X394200Y-1055033D01*
X394900Y-1054633D01*
X395700Y-1054500D01*
X396700Y-1054767D01*
X397400Y-1055433D01*
X397600Y-1056233D01*
X397500Y-1057034D01*
X397100Y-1057700D01*
X395100Y-1059033D01*
X394200Y-1059967D01*
X393600Y-1061300D01*
X393400Y-1062500D01*
X397600D01*
G01X401700Y-1062767D02*
X405300Y-1054500D01*
G01X411500Y-1062500D02*
Y-1054500D01*
X410300Y-1056100D01*
G01Y-1062500D02*
X412700D01*
G01X417600Y-1055833D02*
X418200Y-1055033D01*
X418900Y-1054633D01*
X419700Y-1054500D01*
X420700Y-1054767D01*
X421400Y-1055433D01*
X421600Y-1056233D01*
X421500Y-1057034D01*
X421100Y-1057700D01*
X419100Y-1059033D01*
X418200Y-1059967D01*
X417600Y-1061300D01*
X417400Y-1062500D01*
X421600D01*
G01X425700Y-1062767D02*
X429300Y-1054500D01*
G01X435500Y-1062500D02*
Y-1054500D01*
X434300Y-1056100D01*
G01Y-1062500D02*
X436700D01*
G01X441300Y-1060900D02*
X441900Y-1061833D01*
X442700Y-1062367D01*
X443600Y-1062500D01*
X444400Y-1062367D01*
X445200Y-1061700D01*
X445700Y-1060900D01*
X445800Y-1060100D01*
X445600Y-1059167D01*
X444900Y-1058500D01*
X444200Y-1058233D01*
X443300D01*
G01X444200D02*
X444800Y-1057833D01*
X445300Y-1057167D01*
X445500Y-1056367D01*
X445300Y-1055567D01*
X444800Y-1054900D01*
X443900Y-1054500D01*
X443000Y-1054633D01*
X442100Y-1055167D01*
G01X369300Y-1040000D02*
Y-1032000D01*
X371300D01*
X372100Y-1032400D01*
X372700Y-1032933D01*
X373200Y-1033733D01*
X373600Y-1034667D01*
X373700Y-1036000D01*
X373600Y-1037333D01*
X373200Y-1038267D01*
X372700Y-1039067D01*
X372100Y-1039600D01*
X371300Y-1040000D01*
X369300D01*
G01X377000D02*
X379500Y-1032000D01*
X382000Y-1040000D01*
G01X381100Y-1037200D02*
X377900D01*
G01X385600Y-1040000D02*
Y-1032000D01*
X389400D01*
G01X388000Y-1035867D02*
X385600D01*
G01X395500Y-1032000D02*
X394700Y-1032267D01*
X394100Y-1032933D01*
X393700Y-1033733D01*
X393400Y-1034800D01*
X393300Y-1036000D01*
X393400Y-1037200D01*
X393700Y-1038267D01*
X394100Y-1039067D01*
X394700Y-1039733D01*
X395500Y-1040000D01*
X396300Y-1039733D01*
X396900Y-1039067D01*
X397300Y-1038267D01*
X397600Y-1037200D01*
X397700Y-1036000D01*
X397600Y-1034800D01*
X397300Y-1033733D01*
X396900Y-1032933D01*
X396300Y-1032267D01*
X395500Y-1032000D01*
G01X403500D02*
Y-1040000D01*
G01X401200Y-1032000D02*
X405800D01*
G01X409500Y-1040000D02*
Y-1032000D01*
X411900D01*
X412700Y-1032400D01*
X413300Y-1033333D01*
X413500Y-1034400D01*
X413300Y-1035467D01*
X412800Y-1036267D01*
X411900Y-1036667D01*
X409500D01*
G01X420300Y-1035733D02*
X420700Y-1035333D01*
X421000Y-1034667D01*
X421200Y-1033733D01*
X421000Y-1032933D01*
X420600Y-1032400D01*
X419900Y-1032000D01*
X417200D01*
Y-1040000D01*
X420500D01*
X421200Y-1039467D01*
X421600Y-1038667D01*
X421800Y-1037733D01*
X421600Y-1036800D01*
X421000Y-1036000D01*
X420300Y-1035733D01*
X417200D01*
G01X427500Y-1040000D02*
Y-1032000D01*
X426300Y-1033600D01*
G01Y-1040000D02*
X428700D01*
G01X433000D02*
X435500Y-1032000D01*
X438000Y-1040000D01*
G01X437100Y-1037200D02*
X433900D01*
G01X441600Y-1040000D02*
Y-1032000D01*
X445400D01*
G01X444000Y-1035867D02*
X441600D01*
G01X451500Y-1032000D02*
X450700Y-1032267D01*
X450100Y-1032933D01*
X449700Y-1033733D01*
X449400Y-1034800D01*
X449300Y-1036000D01*
X449400Y-1037200D01*
X449700Y-1038267D01*
X450100Y-1039067D01*
X450700Y-1039733D01*
X451500Y-1040000D01*
X452300Y-1039733D01*
X452900Y-1039067D01*
X453300Y-1038267D01*
X453600Y-1037200D01*
X453700Y-1036000D01*
X453600Y-1034800D01*
X453300Y-1033733D01*
X452900Y-1032933D01*
X452300Y-1032267D01*
X451500Y-1032000D01*
G01X389600Y-1012500D02*
Y-1004500D01*
X393400D01*
G01X392000Y-1008367D02*
X389600D01*
G01X399500Y-1004500D02*
X398700Y-1004767D01*
X398100Y-1005433D01*
X397700Y-1006233D01*
X397400Y-1007300D01*
X397300Y-1008500D01*
X397400Y-1009700D01*
X397700Y-1010767D01*
X398100Y-1011567D01*
X398700Y-1012233D01*
X399500Y-1012500D01*
X400300Y-1012233D01*
X400900Y-1011567D01*
X401300Y-1010767D01*
X401600Y-1009700D01*
X401700Y-1008500D01*
X401600Y-1007300D01*
X401300Y-1006233D01*
X400900Y-1005433D01*
X400300Y-1004767D01*
X399500Y-1004500D01*
G01X407500D02*
Y-1012500D01*
G01X405200Y-1004500D02*
X409800D01*
G01X412500Y-1015167D02*
X418500D01*
G01X421500Y-1012500D02*
Y-1004500D01*
X423900D01*
X424700Y-1004900D01*
X425300Y-1005833D01*
X425500Y-1006900D01*
X425300Y-1007967D01*
X424800Y-1008767D01*
X423900Y-1009167D01*
X421500D01*
G01X429300Y-1012500D02*
Y-1004500D01*
X431300D01*
X432100Y-1004900D01*
X432700Y-1005433D01*
X433200Y-1006233D01*
X433600Y-1007167D01*
X433700Y-1008500D01*
X433600Y-1009833D01*
X433200Y-1010767D01*
X432700Y-1011567D01*
X432100Y-1012100D01*
X431300Y-1012500D01*
X429300D01*
G01X440300Y-1008233D02*
X440700Y-1007833D01*
X441000Y-1007167D01*
X441200Y-1006233D01*
X441000Y-1005433D01*
X440600Y-1004900D01*
X439900Y-1004500D01*
X437200D01*
Y-1012500D01*
X440500D01*
X441200Y-1011967D01*
X441600Y-1011167D01*
X441800Y-1010233D01*
X441600Y-1009300D01*
X441000Y-1008500D01*
X440300Y-1008233D01*
X437200D01*
G01X444500Y-1015167D02*
X450500D01*
G01X456300Y-1008233D02*
X456700Y-1007833D01*
X457000Y-1007167D01*
X457200Y-1006233D01*
X457000Y-1005433D01*
X456600Y-1004900D01*
X455900Y-1004500D01*
X453200D01*
Y-1012500D01*
X456500D01*
X457200Y-1011967D01*
X457600Y-1011167D01*
X457800Y-1010233D01*
X457600Y-1009300D01*
X457000Y-1008500D01*
X456300Y-1008233D01*
X453200D01*
G01X461300Y-1012500D02*
Y-1004500D01*
X463300D01*
X464100Y-1004900D01*
X464700Y-1005433D01*
X465200Y-1006233D01*
X465600Y-1007167D01*
X465700Y-1008500D01*
X465600Y-1009833D01*
X465200Y-1010767D01*
X464700Y-1011567D01*
X464100Y-1012100D01*
X463300Y-1012500D01*
X461300D01*
G01X468500Y-1015167D02*
X474500D01*
G01X480100Y-1008500D02*
X482100D01*
Y-1010900D01*
X481500Y-1011700D01*
X480800Y-1012233D01*
X479800Y-1012500D01*
X478800Y-1012233D01*
X478100Y-1011700D01*
X477500Y-1010900D01*
X477100Y-1009967D01*
X476900Y-1008900D01*
Y-1007967D01*
X477100Y-1007167D01*
X477500Y-1006233D01*
X478100Y-1005433D01*
X478700Y-1004900D01*
X479500Y-1004500D01*
X480200D01*
X481000Y-1004767D01*
X481600Y-1005300D01*
G01X485500Y-1012500D02*
Y-1004500D01*
X487900D01*
X488700Y-1004900D01*
X489300Y-1005833D01*
X489500Y-1006900D01*
X489300Y-1007967D01*
X488800Y-1008767D01*
X487900Y-1009167D01*
X485500D01*
G01X493300Y-1004500D02*
Y-1010233D01*
X493700Y-1011434D01*
X494500Y-1012233D01*
X495500Y-1012500D01*
X496500Y-1012233D01*
X497300Y-1011434D01*
X497700Y-1010233D01*
Y-1004500D01*
G01X458000Y-1065500D02*
Y-1057500D01*
X456800Y-1059100D01*
G01Y-1065500D02*
X459200D01*
G01X464100Y-1062167D02*
X464800Y-1061233D01*
X465400Y-1060700D01*
X466200Y-1060433D01*
X466900Y-1060700D01*
X467400Y-1061233D01*
X467800Y-1062033D01*
X467900Y-1062967D01*
X467800Y-1063767D01*
X467400Y-1064567D01*
X466800Y-1065233D01*
X466100Y-1065500D01*
X465300Y-1065233D01*
X464600Y-1064434D01*
X464200Y-1063233D01*
X464100Y-1061900D01*
X464300Y-1060167D01*
X464600Y-1059233D01*
X465100Y-1058300D01*
X465800Y-1057633D01*
X466500Y-1057500D01*
X467200Y-1057767D01*
X467700Y-1058433D01*
G01X474000Y-1065767D02*
X473800Y-1065633D01*
Y-1065367D01*
X474000Y-1065233D01*
X474200Y-1065367D01*
Y-1065633D01*
X474000Y-1065767D01*
G01X480100Y-1062167D02*
X480800Y-1061233D01*
X481400Y-1060700D01*
X482200Y-1060433D01*
X482900Y-1060700D01*
X483400Y-1061233D01*
X483800Y-1062033D01*
X483900Y-1062967D01*
X483800Y-1063767D01*
X483400Y-1064567D01*
X482800Y-1065233D01*
X482100Y-1065500D01*
X481300Y-1065233D01*
X480600Y-1064434D01*
X480200Y-1063233D01*
X480100Y-1061900D01*
X480300Y-1060167D01*
X480600Y-1059233D01*
X481100Y-1058300D01*
X481800Y-1057633D01*
X482500Y-1057500D01*
X483200Y-1057767D01*
X483700Y-1058433D01*
G01X503000Y-1065500D02*
Y-1057500D01*
X501800Y-1059100D01*
G01Y-1065500D02*
X504200D01*
G01X510800D02*
X511000Y-1063767D01*
X511300Y-1062300D01*
X511700Y-1060967D01*
X512200Y-1059500D01*
X513000Y-1057500D01*
X509000D01*
G01X519000Y-1065767D02*
X518800Y-1065633D01*
Y-1065367D01*
X519000Y-1065233D01*
X519200Y-1065367D01*
Y-1065633D01*
X519000Y-1065767D01*
G01X525100Y-1058833D02*
X525700Y-1058033D01*
X526400Y-1057633D01*
X527200Y-1057500D01*
X528200Y-1057767D01*
X528900Y-1058433D01*
X529100Y-1059233D01*
X529000Y-1060034D01*
X528600Y-1060700D01*
X526600Y-1062033D01*
X525700Y-1062967D01*
X525100Y-1064300D01*
X524900Y-1065500D01*
X529100D01*
G01X523100Y-1040500D02*
Y-1032500D01*
X526900D01*
G01X525500Y-1036367D02*
X523100D01*
G54D86*
X1765686Y396020D03*
X1780056D03*
G54D68*
X1643500Y152925D03*
Y155484D03*
Y158043D03*
Y160602D03*
Y163161D03*
Y165720D03*
Y168280D03*
Y170839D03*
Y173398D03*
Y175957D03*
Y178516D03*
Y181075D03*
X1666500Y178516D03*
Y175957D03*
Y173398D03*
Y170839D03*
Y168280D03*
Y165720D03*
Y163161D03*
Y160602D03*
Y158043D03*
Y155484D03*
Y152925D03*
Y181075D03*
G54D59*
X825900Y382200D03*
Y372200D03*
X866400Y362200D03*
Y372200D03*
X906900Y382200D03*
Y372200D03*
G54D77*
X1732870Y392500D03*
X1754130D03*
G54D96*
G01X1635195Y90940D02*
X1630903D01*
X1630527Y90564D01*
G54D87*
X1848583Y99212D03*
X1848582Y481693D03*
G54D69*
X1653103Y113201D03*
G54D78*
X1746100Y235839D03*
Y253161D03*
G54D97*
G01X1767151Y333311D02*
X1766379Y334083D01*
X1762730D01*
G01X1766249Y339649D02*
X1765408Y338808D01*
X1762730D01*
G01Y332508D02*
X1765192D01*
X1766500Y331200D01*
X1767500D01*
X1769300Y329400D01*
G01X1769692Y334649D02*
X1768683Y335658D01*
X1762730D01*
G01X1771705Y343970D02*
X1769930D01*
X1767700Y346200D01*
G01D02*
Y343800D01*
X1764282Y340382D01*
X1762730D01*
G01Y342351D02*
X1764600Y344221D01*
Y347000D01*
X1767600Y350000D01*
G01D02*
X1769600Y352000D01*
Y354075D01*
X1771825Y356300D01*
G01X1769300Y329400D02*
X1769483Y329583D01*
X1770474D01*
X1771735Y328322D01*
G01X1771833Y348288D02*
Y352305D01*
G01Y348288D02*
Y344098D01*
X1771705Y343970D01*
G54D79*
X1759880Y267724D03*
Y312016D03*
G54D88*
X1835739Y99212D03*
X1835738Y481693D03*
G54D98*
G01X134600Y150000D02*
Y147000D01*
X136100Y145500D01*
X139584D01*
G01X126986D02*
X120840D01*
G01X126986Y136500D02*
X122600D01*
X120840Y138260D01*
Y145500D01*
G01X139584Y127500D02*
X136600D01*
X134600Y129500D01*
Y134000D01*
G01D02*
X137100Y136500D01*
X139584D01*
G01X130915Y120500D02*
X124600D01*
G01D02*
Y125114D01*
X126986Y127500D01*
G01Y163500D02*
X121100D01*
G01X126986Y154500D02*
X122600D01*
X121100Y156000D01*
Y163500D01*
G01X139584Y154500D02*
X136600D01*
X134600Y152500D01*
Y150000D01*
G01X190950Y106500D02*
X187600D01*
G01X191885Y119000D02*
Y107435D01*
X190950Y106500D01*
G01X191885Y119000D02*
Y129486D01*
X192600Y130201D01*
G01X208000Y106075D02*
X211425D01*
G01X200685Y115000D02*
X204985Y110700D01*
X206900D01*
G01D02*
X208000Y111800D01*
Y115425D01*
G01Y102925D02*
X202924D01*
G01D02*
X198266D01*
X197250Y103941D01*
G01X208000Y118575D02*
X210925Y115650D01*
Y115575D01*
G01X317000Y72075D02*
Y74475D01*
G01Y68925D02*
Y64500D01*
G01X321500Y72075D02*
Y74475D01*
G01Y68925D02*
Y66500D01*
G01X326000Y68925D02*
Y64900D01*
X325100Y64000D01*
G01X332500Y63300D02*
X330500Y65300D01*
Y68925D01*
G01Y72075D02*
Y74476D01*
G01X326000Y72075D02*
Y74476D01*
G01X392000Y46875D02*
X387060Y51815D01*
Y55500D01*
G01X392000Y46875D02*
X396216D01*
G01X436500Y175600D02*
X437900Y174200D01*
X440100D01*
X443600Y170700D01*
G01X437200Y219100D02*
X439400D01*
X443400Y215100D01*
G01X444838Y81900D02*
X439400D01*
G01X444838Y126300D02*
X439500D01*
G01X444838Y170700D02*
X443600D01*
G01X444838Y215100D02*
X443400D01*
G01X444838Y259500D02*
X438800D01*
G01X444838Y303900D02*
X439100D01*
G01X605800Y256500D02*
Y256600D01*
X608500Y259300D01*
Y268501D01*
X601236Y275765D01*
Y288920D01*
X598500Y291656D01*
Y306500D01*
X604407Y312407D01*
X622093D01*
X630000Y304500D01*
X662100D01*
G01X670184Y288500D02*
Y285604D01*
X662362Y277782D01*
X653966D01*
X640684Y264500D01*
G01Y269000D02*
X652184Y280500D01*
X662184D01*
G01X645900Y242200D02*
X638168D01*
X629018Y251350D01*
Y277500D01*
G01X625684Y273499D02*
Y244245D01*
X620600Y239161D01*
G01X630308Y284500D02*
X632731Y282077D01*
Y252065D01*
X637957Y246839D01*
X644502D01*
G01X649500Y257425D02*
Y254800D01*
X649200Y254500D01*
G01D02*
X649640Y254060D01*
X655319D01*
X657259Y256000D01*
G01X650500Y246600D02*
X646900Y250200D01*
Y251500D01*
G01X623684Y281000D02*
Y283384D01*
X627400Y287100D01*
X631800D01*
X634611Y284289D01*
Y279388D01*
X636099Y277900D01*
X642300D01*
X655800Y291400D01*
X670100D01*
X672600Y288900D01*
Y282034D01*
X673684Y280950D01*
G01X649500Y308500D02*
X650000Y309000D01*
X654925D01*
X663500Y317575D01*
G01X649500Y308500D02*
X633500D01*
X631000Y311000D01*
Y313760D01*
G01D02*
X645260D01*
X646500Y315000D01*
Y317260D01*
G01X649059Y324740D02*
X651299Y322500D01*
X658925D01*
G01X683592Y259908D02*
X681684Y258000D01*
Y235940D01*
X676638Y230894D01*
G01X666759Y260500D02*
X664319Y258060D01*
X659699D01*
X657259Y260500D01*
G01D02*
Y263000D01*
G01X666759Y260500D02*
X668684Y262425D01*
Y272159D01*
X672465Y275940D01*
X676144D01*
X679184Y278980D01*
G01X657259Y266000D02*
X658199Y266940D01*
X664319D01*
X666759Y264500D01*
G01X654100Y263000D02*
X654259D01*
X657259Y266000D01*
G01X666759Y264500D02*
Y274800D01*
G01X663609Y256000D02*
X657259D01*
G01X679184Y273190D02*
Y263925D01*
X666759Y251500D01*
G01X676184Y274000D02*
X673900D01*
X671400Y271500D01*
Y261000D01*
G01D02*
Y260641D01*
X666759Y256000D01*
G01X663609Y251500D02*
X657259D01*
G01D02*
X654759Y249000D01*
X652900D01*
X650500Y246600D01*
G01X673684Y280950D02*
X710900Y318166D01*
Y324100D01*
G01X666759Y274800D02*
X669779Y277820D01*
X675364D01*
X676684Y279140D01*
Y280950D01*
G01X662100Y304500D02*
X671525D01*
X677525Y298500D01*
G01X674276Y323240D02*
X670340D01*
X668000Y320900D01*
G01D02*
X664675Y317575D01*
X663500D01*
G01X714045Y326886D02*
X709566D01*
X702180Y319500D01*
X674276D01*
G01X658925Y322500D02*
Y320000D01*
G01X691575Y178500D02*
X692075Y178000D01*
X696760D01*
G01X704240D02*
Y185000D01*
G01X719433Y328087D02*
X726996D01*
X741630Y313453D01*
Y253986D01*
X733864Y246220D01*
X726105D01*
X714166Y234281D01*
Y214577D01*
X709261Y209672D01*
X702745D01*
X701377Y208304D01*
Y206176D01*
X686941Y191740D01*
X682163D01*
G01X702223Y197419D02*
Y196314D01*
X705037Y193500D01*
G01X690037Y188000D02*
Y192176D01*
X695101Y197240D01*
X697163D01*
G01X691575Y178500D02*
X690900Y179175D01*
Y186785D01*
X690037Y187648D01*
Y188000D01*
G01X717401Y329996D02*
X718571Y331166D01*
X726576D01*
X743510Y314232D01*
Y253207D01*
X734643Y244340D01*
X726884D01*
X716046Y233502D01*
Y213798D01*
X704278Y202030D01*
X702153D01*
X697363Y197240D01*
X697163D01*
G01X689684Y230762D02*
Y249159D01*
X692025Y251500D01*
G01X681684Y230820D02*
X685741Y234877D01*
Y260543D01*
X687339Y262141D01*
X690726D01*
X691794Y261073D01*
G01X692025Y255500D02*
Y251500D01*
G01Y255500D02*
Y256681D01*
X688945Y259761D01*
G01X680675Y298500D02*
Y302500D01*
G01X685884Y297000D02*
X684384Y298500D01*
X680675D01*
G01X710900Y324100D02*
X709685D01*
X701345Y315760D01*
X683724D01*
G01X997833Y593187D02*
X703029D01*
X702349Y593867D01*
Y602507D01*
X703029Y603187D01*
X997833D01*
G01X723000Y312740D02*
Y310851D01*
X723867Y309984D01*
X727714D01*
X731131Y313401D01*
X736028D01*
X739464Y309965D01*
Y254884D01*
X732966Y248386D01*
X725207D01*
X712000Y235179D01*
Y215500D01*
G01X725000Y292500D02*
X719484Y286984D01*
Y278980D01*
G01X723000Y312740D02*
Y317931D01*
X714045Y326886D01*
G01X718000Y300000D02*
Y302819D01*
X720441Y305260D01*
G01X727236Y300595D02*
X725699Y302132D01*
X720132D01*
X718000Y300000D01*
G01X727236Y300595D02*
X726141Y299500D01*
X722925D01*
G01X825900Y362200D02*
X809400D01*
G01X866400Y382200D02*
X874825D01*
X875025Y382000D01*
G01X866400Y362200D02*
X874825D01*
X875025Y362000D01*
G01X878175Y374100D02*
Y382000D01*
G01Y362000D02*
Y364709D01*
G01X906900Y362200D02*
X923100D01*
G01X1029063Y201500D02*
X1026669Y203894D01*
Y209094D01*
X1027675Y210100D01*
Y215000D01*
G01X1037600Y188925D02*
X1046462D01*
X1047100Y189563D01*
G01X1031840Y190500D02*
X1033415Y188925D01*
X1037600D01*
G01X1034537Y201437D02*
Y200160D01*
X1036937Y197760D01*
G01D02*
X1034537D01*
X1031840Y195063D01*
Y190500D01*
G01X1024360D02*
Y185240D01*
X1024600Y185000D01*
G01X1123400Y356300D02*
Y353400D01*
X1101620Y331620D01*
X1064779D01*
X1034370Y301211D01*
X1023517D01*
X1018217Y295911D01*
Y254444D01*
X1037301Y235360D01*
Y231776D01*
X1024525Y219000D01*
Y215000D01*
G01X1088079Y274980D02*
X1082316D01*
X1079100Y271764D01*
Y262812D01*
X1076288Y260000D01*
X1056738D01*
X1041103Y244365D01*
X1030955D01*
X1020097Y255223D01*
Y295132D01*
X1024296Y299331D01*
X1035149D01*
X1065558Y329740D01*
X1103740D01*
X1132000Y358000D01*
Y367000D01*
G01X1034360Y254000D02*
X1042800Y262440D01*
Y273020D01*
G01X1026270Y303729D02*
X1034229D01*
X1064000Y333500D01*
X1098841D01*
X1106163Y340822D01*
Y348837D01*
X1094500Y360500D01*
G01X1050840Y197437D02*
X1047163D01*
G01X1072600Y324000D02*
X1078100Y318500D01*
Y291300D01*
X1076659Y289859D01*
X1071558D01*
X1070490Y290927D01*
G01X1069675Y311500D02*
Y307500D01*
G01D02*
X1076100Y301075D01*
Y295000D01*
X1073339Y292239D01*
G01X1069675Y311500D02*
Y318925D01*
X1064600Y324000D01*
G01X1092100Y263500D02*
X1094600Y266000D01*
X1111700D01*
X1123900Y278200D01*
Y285200D01*
X1121600Y287500D01*
G01X1100100Y247500D02*
X1092100Y255500D01*
X1085675D01*
G01X1082525Y251500D02*
Y255500D01*
G01X1074430Y256461D02*
X1075391Y255500D01*
X1082525D01*
G01X1095525Y287500D02*
Y276425D01*
X1090150Y271050D01*
X1085600D01*
G01X1105025Y285000D02*
X1098025D01*
X1095525Y287500D01*
G01X1101500Y271500D02*
X1113685D01*
X1121600Y279415D01*
Y283000D01*
G01X1095525Y291500D02*
X1097965Y293940D01*
X1102585D01*
X1105025Y291500D01*
G01X1091800Y279100D02*
X1093600Y280900D01*
Y289575D01*
X1095525Y291500D01*
G01X1091800Y279100D02*
Y275359D01*
X1089461Y273020D01*
X1083100D01*
G01X1080600Y294000D02*
Y324000D01*
G01X1098675Y296000D02*
X1099000D01*
X1100940Y297940D01*
X1106859D01*
X1108175Y296624D01*
Y296000D01*
G01X1083100Y278810D02*
X1084600Y280310D01*
Y284000D01*
X1087100Y286500D01*
Y292075D01*
X1095525Y300500D01*
G01Y296000D02*
X1090200Y290675D01*
Y288600D01*
G01D02*
Y282100D01*
X1086100Y278000D01*
G01X1098675Y300500D02*
X1105025D01*
G01X1131976Y267500D02*
X1130100Y269376D01*
Y305174D01*
G01X1105025Y285000D02*
Y285925D01*
X1108100Y289000D01*
G01X1141500Y347500D02*
X1139000Y345000D01*
X1127000D01*
X1120000Y338000D01*
Y318100D01*
X1126400Y311700D01*
Y293800D01*
X1121600Y289000D01*
Y287500D01*
G01X1138500Y347500D02*
X1126000D01*
X1117600Y339100D01*
Y316785D01*
X1123912Y310473D01*
Y294630D01*
X1119000Y289718D01*
Y285600D01*
X1121600Y283000D01*
G01X1105025Y291500D02*
Y289000D01*
G01X1132113Y274500D02*
Y276713D01*
X1133100Y277700D01*
G01D02*
Y305130D01*
X1130510Y307720D01*
G01X1108175Y296000D02*
X1112000D01*
G01D02*
X1115025D01*
G01X1112136Y305400D02*
X1110283Y303547D01*
X1108072D01*
X1105025Y300500D01*
G01X1114600D02*
Y302936D01*
X1112136Y305400D01*
G01X1156584Y292488D02*
X1158548Y294452D01*
Y296552D01*
X1152180Y302920D01*
Y334180D01*
X1159985Y341985D01*
Y346485D01*
X1166000Y352500D01*
G01X1156509Y295396D02*
X1150300Y301605D01*
Y334959D01*
X1158105Y342764D01*
Y347605D01*
X1163000Y352500D01*
G01X1136000Y278953D02*
X1135194Y279759D01*
Y306433D01*
X1141600Y312839D01*
G01X1317446Y62100D02*
X1323900D01*
G01X1317446Y106500D02*
X1323500D01*
G01X1318900Y150900D02*
X1324000Y156000D01*
G01X1317446Y150900D02*
X1318900D01*
G01X1317446Y195300D02*
X1320300D01*
X1324000Y199000D01*
G01X1317446Y239700D02*
X1323700D01*
G01X1317446Y284100D02*
X1323000D01*
G01X1494728Y72076D02*
Y83500D01*
G01X1490000Y80500D02*
X1490228Y80272D01*
Y72076D01*
G01X1494728Y68926D02*
Y66500D01*
G01X1490228Y68926D02*
Y66500D01*
G01X1498180Y63500D02*
X1499228Y64548D01*
Y68926D01*
G01Y72076D02*
Y74500D01*
G01X1505100Y64500D02*
Y67554D01*
X1503728Y68926D01*
G01Y72076D02*
Y74477D01*
G01X1524500Y98925D02*
X1527100D01*
G01X1529400Y102075D02*
X1524500D01*
G01X1524600Y119500D02*
X1521925Y116825D01*
Y114500D01*
G01X1525075D02*
X1524600Y114025D01*
Y111500D01*
G01X1531100Y116500D02*
X1528100Y119500D01*
X1524600D01*
G01X1534850Y102059D02*
X1534834Y102075D01*
X1529400D01*
G01X1541150Y99500D02*
Y111250D01*
X1539900Y112500D01*
G01D02*
Y123401D01*
X1539600Y123701D01*
G01X1541150Y99500D02*
X1544150Y96500D01*
X1551000D01*
G01D02*
X1553600D01*
X1555500Y98400D01*
Y104251D01*
G01X1607100Y115000D02*
X1601370D01*
G01X1605299Y122000D02*
X1607100Y120199D01*
Y115000D01*
G01X1592701Y140000D02*
X1595600D01*
X1597100Y141500D01*
Y145000D01*
G01D02*
Y147501D01*
X1595601Y149000D01*
X1592701D01*
G01X1605299Y140000D02*
X1609600D01*
X1611100Y138500D01*
G01D02*
Y133001D01*
X1609099Y131000D01*
X1605299D01*
G01X1592701D02*
X1595600D01*
X1597100Y129500D01*
Y126000D01*
G01D02*
Y123499D01*
X1595601Y122000D01*
X1592701D01*
G01X1605299Y149000D02*
X1610100D01*
X1612100Y151000D01*
Y154000D01*
G01D02*
Y156000D01*
X1610100Y158000D01*
X1605299D01*
G01X1615575Y173000D02*
X1618000D01*
X1620500Y170500D01*
G01X1615575Y165500D02*
Y164925D01*
X1621500Y159000D01*
G01Y165000D02*
X1620075D01*
X1615575Y169500D01*
G01X1632336Y109117D02*
Y110645D01*
X1632923Y111232D01*
X1634451D01*
G01X1628960D02*
X1630221D01*
X1632336Y109117D01*
G01X1620960Y111232D02*
X1624940D01*
G01D02*
X1628960D01*
G01X1634451Y115168D02*
X1631351D01*
X1631323Y115140D01*
G01D02*
X1627845D01*
G01X1631600Y156937D02*
Y147734D01*
X1627366Y143500D01*
G01D02*
X1628866Y142000D01*
X1632025D01*
G01X1647837Y118712D02*
Y121812D01*
G01X1645868Y118712D02*
Y122774D01*
X1647103Y124009D01*
X1650258D01*
X1651325Y125076D01*
G01X1645280Y127425D02*
X1644917Y127062D01*
Y124581D01*
G01D02*
X1643900Y123564D01*
Y118712D01*
G01X1641932D02*
Y122969D01*
G01X1638770Y127365D02*
X1641932Y124203D01*
Y122969D01*
G01X1627845Y119140D02*
Y121206D01*
X1626951Y122100D01*
X1619803D01*
X1618177Y120474D01*
G01X1667600Y198500D02*
X1662000Y192900D01*
Y188000D01*
X1660500Y186500D01*
Y165023D01*
X1658600Y163123D01*
Y163000D01*
X1645600Y150000D01*
X1643175D01*
X1635175Y142000D01*
G01X1620500Y170500D02*
X1621000Y170000D01*
X1627075D01*
X1629575Y172500D01*
G01D02*
X1633032Y175957D01*
X1643500D01*
G01Y178516D02*
X1638115D01*
X1637599Y178000D01*
X1629575D01*
G01X1620000Y177500D02*
X1618500Y179000D01*
Y182425D01*
G01X1629575Y178000D02*
Y179424D01*
X1628499Y180500D01*
X1621000D01*
X1620000Y179500D01*
Y177500D01*
G01X1650117Y180000D02*
Y176084D01*
X1651617Y174584D01*
Y167617D01*
X1647161Y163161D01*
X1643500D01*
G01X1657500Y191500D02*
X1654080Y188080D01*
Y177439D01*
X1655380Y176139D01*
Y165221D01*
X1648202Y158043D01*
X1643500D01*
G01Y170839D02*
X1646339D01*
X1647500Y172000D01*
Y188999D01*
X1655501Y197000D01*
X1663000D01*
X1664000Y198000D01*
Y202500D01*
G01X1636600Y173500D02*
X1636702Y173398D01*
X1643500D01*
G01X1622100Y148925D02*
X1618100D01*
G01X1622100D02*
X1624175Y151000D01*
X1625923D01*
X1627860Y149063D01*
G01X1622100Y155931D02*
Y152075D01*
G01X1628425Y163500D02*
X1626000D01*
G01X1621500Y159000D02*
X1626000Y163500D01*
G01X1628425Y167500D02*
X1626000D01*
G01D02*
X1623500Y165000D01*
X1621500D01*
G01X1643500Y168280D02*
X1636780D01*
X1636500Y168000D01*
G01X1631575Y167500D02*
X1636000D01*
X1636500Y168000D01*
G01Y162500D02*
X1639720Y165720D01*
X1643500D01*
G01X1631575Y163500D02*
X1635500D01*
X1636500Y162500D01*
G01X1654000Y192500D02*
X1652200Y190700D01*
Y176660D01*
X1653500Y175360D01*
Y166000D01*
X1648102Y160602D01*
X1643500D01*
G01Y155484D02*
X1648302D01*
X1657260Y164442D01*
Y176918D01*
X1655960Y178218D01*
Y184960D01*
X1660000Y189000D01*
Y193500D01*
G01X1643037Y191000D02*
X1646001D01*
X1648925Y193924D01*
Y194000D01*
G01X1634200Y180500D02*
X1634775Y181075D01*
X1643500D01*
G01X1629575Y183000D02*
X1632075Y180500D01*
X1634200D01*
G01X1624000Y189000D02*
X1626175D01*
X1629600Y192425D01*
G01X1635163Y194740D02*
X1630435D01*
X1629600Y195575D01*
G01X1628840Y202500D02*
Y196335D01*
X1629600Y195575D01*
G01X1635163Y194740D02*
Y200500D01*
G01D02*
X1636412D01*
X1637337Y201425D01*
X1641000D01*
G01X1650990Y122034D02*
X1649806Y120850D01*
Y118712D01*
G01X1656657Y127365D02*
X1653270D01*
G01X1651774Y118613D02*
Y120073D01*
X1654030Y122329D01*
Y126027D01*
X1653270Y126787D01*
Y127365D01*
G01X1649270D02*
X1650446D01*
X1651325Y126486D01*
Y125076D01*
G01X1705100Y140500D02*
X1681840D01*
X1669414Y152926D01*
Y152925D01*
X1666500D01*
G01X1707100Y142500D02*
X1682499D01*
X1669515Y155484D01*
X1666500D01*
G01X1685000Y133000D02*
X1682515Y130515D01*
X1653270D01*
G01X1666500Y175957D02*
X1669682D01*
X1677945Y184220D01*
X1688100D01*
G01X1666500Y173398D02*
X1670348D01*
X1672950Y176000D01*
X1674600D01*
G01D02*
X1679600Y181000D01*
X1680425D01*
G01Y170000D02*
X1678705Y168280D01*
X1674100D01*
G01D02*
X1666500D01*
G01X1680425Y175500D02*
X1677925Y173000D01*
X1673100D01*
X1670939Y170839D01*
X1666500D01*
G01Y165720D02*
X1679205D01*
X1680425Y164500D01*
G01X1666500Y158043D02*
X1670382D01*
X1675985Y152440D01*
X1676010D01*
X1677439Y151011D01*
Y150986D01*
X1680425Y148000D01*
G01Y159000D02*
X1677601D01*
X1676350Y160251D01*
G01D02*
X1673440Y163161D01*
X1666500D01*
G01X1680425Y153500D02*
X1678600D01*
X1673600Y158500D01*
G01D02*
X1671498Y160602D01*
X1666500D01*
G01X1680425Y186500D02*
X1677000D01*
X1672050Y181550D01*
G01D02*
X1668936Y178436D01*
X1666580D01*
X1666500Y178516D01*
G01X1648925Y194000D02*
X1652425Y197500D01*
Y199000D01*
G01X1655575D02*
X1661500D01*
G01X1701100Y86500D02*
Y90500D01*
X1702600Y92000D01*
X1706100D01*
G01X1713125Y99000D02*
X1698100D01*
X1691100Y92000D01*
Y86500D01*
G01X1713125Y93500D02*
X1711125Y95500D01*
X1700100D01*
X1696100Y91500D01*
Y86500D01*
G01X1706100Y92000D02*
X1709125D01*
X1713125Y88000D01*
G01X1690100Y116000D02*
Y121825D01*
G01X1696100Y107300D02*
Y110000D01*
X1690100Y116000D01*
G01X1700100Y121825D02*
Y115500D01*
X1701350Y114250D01*
G01D02*
X1706100Y109500D01*
Y107300D01*
G01X1696600Y119000D02*
Y115000D01*
X1701100Y110500D01*
Y107300D01*
G01X1690100Y121825D02*
X1690924D01*
X1693000Y123901D01*
Y131101D01*
X1691276Y132825D01*
X1690100D01*
G01X1702600Y171500D02*
X1703500Y170600D01*
Y152549D01*
X1705000Y151049D01*
X1708420D01*
X1709100Y150369D01*
Y148949D01*
X1708420Y148269D01*
X1700780D01*
X1700100Y147589D01*
Y146169D01*
X1700780Y145489D01*
X1708420D01*
X1709380Y144529D01*
Y141279D01*
X1706321Y138220D01*
X1704319D01*
X1703299Y137200D01*
X1700200D01*
X1696000Y133000D01*
Y126575D01*
X1697600Y124975D01*
X1700100D01*
G01X1708075Y134500D02*
X1710575Y132000D01*
X1716575D01*
X1719075Y134500D01*
G01X1708075Y129500D02*
Y124025D01*
G01D02*
X1713600D01*
X1719075Y129500D01*
G01X1692425Y148000D02*
X1689985Y145560D01*
X1688100D01*
G01D02*
X1682865D01*
X1680425Y148000D01*
G01X1707200Y163575D02*
Y166152D01*
X1708014Y166966D01*
X1709086D01*
X1709900Y167780D01*
Y168932D01*
X1709086Y169746D01*
X1708014D01*
X1707200Y170560D01*
Y172100D01*
X1708100Y173000D01*
X1711100D01*
X1711600Y173500D01*
Y174320D01*
X1710920Y175000D01*
X1703780D01*
X1703100Y175680D01*
Y177820D01*
X1703780Y178500D01*
X1712600D01*
X1713245Y179145D01*
Y180820D01*
X1712565Y181500D01*
X1701600D01*
X1701100Y182000D01*
G01X1680425Y170000D02*
X1682865Y167560D01*
X1689985D01*
X1692425Y170000D01*
G01Y175500D02*
X1689985Y173060D01*
X1688100D01*
G01D02*
X1682865D01*
X1680425Y175500D01*
G01X1692425Y164500D02*
X1689985Y162060D01*
X1688100D01*
G01D02*
X1682865D01*
X1680425Y164500D01*
G01Y159000D02*
X1682865Y156560D01*
X1689985D01*
X1692425Y159000D01*
G01X1680425Y153500D02*
X1682865Y151060D01*
X1689985D01*
X1692425Y153500D01*
G01X1712000Y160425D02*
X1707200D01*
G01D02*
Y158680D01*
X1707880Y158000D01*
X1709600D01*
G01X1683575Y186500D02*
X1685975D01*
G01X1695575D02*
X1696575Y185500D01*
X1701025D01*
Y182075D01*
X1701100Y182000D01*
G01X1688100Y184220D02*
X1690145D01*
X1692425Y186500D01*
G01X1680425Y181000D02*
X1682925Y178500D01*
X1689925D01*
X1692425Y181000D01*
G01X1707500Y195425D02*
X1710424D01*
X1713999Y199000D01*
X1717499D01*
X1721500Y203001D01*
Y205000D01*
G01X1707500Y198575D02*
Y201000D01*
X1710000Y203500D01*
G01X1706075Y208000D02*
X1707500Y206575D01*
Y206000D01*
X1710000Y203500D01*
G01X1715376Y202240D02*
X1713081D01*
X1709324Y198483D01*
X1707592D01*
X1707500Y198575D01*
G01X1713125Y88000D02*
X1715565Y90440D01*
X1721685D01*
X1724125Y88000D01*
G01X1732100Y109500D02*
X1719075D01*
G01D02*
Y107016D01*
G01X1732100Y114500D02*
X1719075D01*
G01D02*
Y112000D01*
G01X1713125Y99000D02*
Y103525D01*
X1714100Y104500D01*
G01D02*
X1721100D01*
X1724125Y101475D01*
Y99000D01*
G01Y93500D02*
X1721685Y95940D01*
G01D02*
X1715565D01*
X1713125Y93500D01*
G01X1732100Y134500D02*
X1724600D01*
G01D02*
X1719075D01*
G01X1732100Y129500D02*
X1719075D01*
G01X1732100Y124500D02*
X1738000D01*
G01X1721000Y144925D02*
Y142525D01*
G01X1733711Y146220D02*
X1733630Y146301D01*
X1725801D01*
X1724425Y144925D01*
X1721000D01*
G01X1711600D02*
X1714100D01*
G01X1732100Y119500D02*
X1724600D01*
G01D02*
X1719075D01*
G01X1712000Y163575D02*
X1716500D01*
G01D02*
X1721000D01*
G01X1733711Y164280D02*
X1727100D01*
G01D02*
X1724281D01*
X1723576Y163575D01*
X1721000D01*
G01X1717925Y168500D02*
X1715525D01*
G01X1717925Y153000D02*
X1715525D01*
G01Y168500D02*
Y178925D01*
X1720100Y183500D01*
X1722925D01*
G01X1733711Y161720D02*
X1725720D01*
X1724425Y160425D01*
X1721000D01*
G01D02*
Y158025D01*
X1722063Y156962D01*
G01X1733711Y166839D02*
X1728260D01*
X1726600Y168499D01*
Y168500D01*
G01D02*
X1721075D01*
G01X1721000Y148075D02*
X1723576D01*
X1724281Y148780D01*
X1726100D01*
G01D02*
X1733711D01*
G01X1711600Y148075D02*
X1717100D01*
G01D02*
X1721000D01*
G01X1733711Y151339D02*
X1727760D01*
X1726099Y153000D01*
G01D02*
X1721075D01*
G01X1726075Y175000D02*
Y179500D01*
G01Y175000D02*
X1728475D01*
G01X1737677Y177500D02*
X1731883D01*
X1729792Y179591D01*
X1726166D01*
X1726075Y179500D01*
G01X1731260Y188063D02*
X1727587D01*
X1723024Y183500D01*
X1722925D01*
G01X1735075Y201500D02*
X1734983Y201408D01*
Y199676D01*
X1735000Y199659D01*
Y195937D01*
G01X1737677Y181240D02*
X1739241D01*
X1744500Y186499D01*
Y187500D01*
G01D02*
X1744000Y188000D01*
Y192575D01*
X1735075Y201500D01*
G01X1724824Y194760D02*
X1721600D01*
G01X1724824Y198500D02*
X1721600D01*
G01X1731000Y245370D02*
X1725052D01*
X1724922Y245500D01*
G01X1728925Y250000D02*
X1727001D01*
X1724922Y247921D01*
Y245500D01*
G01X1767525Y116500D02*
Y114016D01*
G01Y116500D02*
X1763601D01*
X1761601Y114500D01*
X1759600D01*
G01D02*
X1752900D01*
G01Y109500D02*
X1767425D01*
G01D02*
Y107000D01*
G01X1752900Y104500D02*
X1761100D01*
G01D02*
X1767425D01*
G01X1752900Y129500D02*
X1761600D01*
G01D02*
X1767425D01*
G01X1761600Y124524D02*
Y124500D01*
X1752900D01*
G01X1767425D02*
X1761624D01*
X1761600Y124524D01*
G01X1764000Y144925D02*
Y142525D01*
G01Y144925D02*
X1757576D01*
X1756281Y146220D01*
X1751289D01*
G01X1767525Y120500D02*
X1765100D01*
X1764100Y119500D01*
G01X1751289Y143661D02*
X1755339D01*
X1759000Y140000D01*
G01X1752900Y119500D02*
X1760500D01*
G01X1773000Y163575D02*
X1768500D01*
G01D02*
X1764000D01*
G01X1751289Y164280D02*
X1758600D01*
G01D02*
X1761455D01*
X1762160Y163575D01*
X1764000D01*
G01X1766925Y174000D02*
X1763075D01*
G01X1772600Y177300D02*
X1770225D01*
X1766925Y174000D01*
G01X1764000Y160425D02*
Y158025D01*
G01Y160425D02*
X1761576D01*
X1760281Y161720D01*
X1751289D01*
G01X1764000Y148075D02*
X1762160D01*
X1761455Y148780D01*
X1758600D01*
G01X1773000Y148075D02*
X1768500D01*
G01D02*
X1764000D01*
G01X1758600Y148780D02*
X1751289D01*
G01Y159161D02*
X1755839D01*
X1759000Y156000D01*
G01X1759925Y174000D02*
X1755000D01*
G01D02*
X1754760Y173760D01*
X1747323D01*
G01X1750563Y194740D02*
Y198000D01*
G01X1751075Y200500D02*
X1750563Y199988D01*
Y198000D01*
G01X1747925Y200500D02*
Y204000D01*
G01X1758437Y191000D02*
Y200138D01*
X1758075Y200500D01*
G01D02*
X1763000D01*
G01D02*
Y196303D01*
X1764563Y194740D01*
G01X1770575Y129500D02*
X1775320Y134245D01*
Y155680D01*
X1773000Y158000D01*
G01Y144925D02*
Y142525D01*
G01X1770675Y120500D02*
Y124400D01*
X1770575Y124500D01*
G01D02*
X1772975D01*
G01X1773000Y160425D02*
Y158000D01*
G01X1778000Y192425D02*
Y189500D01*
G01X1772437Y191000D02*
Y200362D01*
X1772575Y200500D01*
G01X1778000Y195575D02*
Y200500D01*
G01D02*
X1772575D01*
G01X1795600Y308000D02*
Y339500D01*
X1791130Y343970D01*
X1774855D01*
G01X1842164Y421663D02*
Y419238D01*
G01X1847164Y421663D02*
Y419238D01*
G01X1837164Y421663D02*
Y419238D01*
G01X1852164Y421663D02*
Y419238D01*
G01X1842164Y424813D02*
Y432338D01*
G01X1847164Y430568D02*
Y424813D01*
G01X1852164D02*
Y435538D01*
G01X1837164Y424813D02*
Y428238D01*
G54D89*
X1846142Y230433D03*
Y240433D03*
X1856772D03*
Y230433D03*
X1846142Y250433D03*
Y260433D03*
Y270433D03*
X1856772D03*
Y260433D03*
Y250433D03*
X1846142Y280433D03*
Y290433D03*
Y300433D03*
X1856772D03*
Y290433D03*
Y280433D03*
X1848957Y324213D03*
X1843957Y329213D03*
X1848957Y314213D03*
X1843957Y319213D03*
X1853957Y329213D03*
Y319213D03*
X1858957Y324213D03*
Y314213D03*
X1848957Y334213D03*
Y344213D03*
X1843957Y339213D03*
Y349213D03*
X1853957D03*
Y339213D03*
X1858957Y344213D03*
Y334213D03*
M02*
